G04 ================== begin FILE IDENTIFICATION RECORD ==================*
G04 Layout Name:  D:/<user>/Wistron_project/16315-1/gbr/16315-1.brd*
G04 Film Name:    L6VCC*
G04 File Format:  Gerber RS274X*
G04 File Origin:  Cadence Allegro 16.5-S056*
G04 Origin Date:  Fri Jun 09 15:31:41 2017*
G04 *
G04 Layer:  VIA CLASS/L6VCC*
G04 Layer:  PIN/L6VCC*
G04 Layer:  PACKAGE GEOMETRY/PWRVCC*
G04 Layer:  ETCH/L6VCC*
G04 Layer:  DRAWING FORMAT/LAYER_PCB_STORY*
G04 Layer:  DRAWING FORMAT/LAYER_L6VCC*
G04 *
G04 Offset:    (0.00 0.00)*
G04 Mirror:    No*
G04 Mode:      Negative*
G04 Rotation:  0*
G04 FullContactRelief:  No*
G04 UndefLineWidth:     6.00*
G04 ================== end FILE IDENTIFICATION RECORD ====================*
%FSLAX35Y35*MOIN*%
%IR0*IPPOS*OFA0.00000B0.00000*MIA0B0*SFA1.00000B1.00000*%
%ADD23C,.03*%
%ADD12C,.032*%
%ADD34C,.034*%
%ADD27C,.043*%
%ADD21C,.081*%
%ADD11C,.036*%
%ADD28C,.047*%
%ADD20C,.065*%
%ADD38C,.057*%
%ADD42C,.058*%
%AMMACRO30*
4,1,15,.00398,.00044,
.003999,.000208,
.004004,-.000025,
.003996,-.000258,
.00398,-.00044,
.00483,-.00129,
.004897,-.001007,
.004947,-.000721,
.004981,-.000432,
.004997,-.000141,
.004997,.000149,
.00498,.00044,
.004946,.000729,
.004895,.001015,
.00483,.00129,
.00398,.00044,
90.*
4,1,15,.00044,-.00398,
.000208,-.003999,
-.000025,-.004004,
-.000258,-.003996,
-.00044,-.00398,
-.00129,-.00483,
-.001007,-.004897,
-.000721,-.004947,
-.000432,-.004981,
-.000141,-.004997,
.000149,-.004997,
.00044,-.00498,
.000729,-.004946,
.001015,-.004895,
.00129,-.00483,
.00044,-.00398,
90.*
4,1,15,-.00398,-.00044,
-.003999,-.000208,
-.004004,.000025,
-.003996,.000258,
-.00398,.00044,
-.00483,.00129,
-.004897,.001007,
-.004947,.000721,
-.004981,.000432,
-.004997,.000141,
-.004997,-.000149,
-.00498,-.00044,
-.004946,-.000729,
-.004895,-.001015,
-.00483,-.00129,
-.00398,-.00044,
90.*
4,1,15,-.00044,.00398,
-.000208,.003999,
.000025,.004004,
.000258,.003996,
.00044,.00398,
.00129,.00483,
.001007,.004897,
.000721,.004947,
.000432,.004981,
.000141,.004997,
-.000149,.004997,
-.00044,.00498,
-.000729,.004946,
-.001015,.004895,
-.00129,.00483,
-.00044,.00398,
90.*
%
%ADD30MACRO30*%
%AMMACRO36*
4,1,15,-.00398,.00044,
-.003999,.000208,
-.004004,-.000025,
-.003996,-.000258,
-.00398,-.00044,
-.00483,-.00129,
-.004897,-.001007,
-.004947,-.000721,
-.004981,-.000432,
-.004997,-.000141,
-.004997,.000149,
-.00498,.00044,
-.004946,.000729,
-.004895,.001015,
-.00483,.00129,
-.00398,.00044,
90.*
4,1,15,-.00044,-.00398,
-.000208,-.003999,
.000025,-.004004,
.000258,-.003996,
.00044,-.00398,
.00129,-.00483,
.001007,-.004897,
.000721,-.004947,
.000432,-.004981,
.000141,-.004997,
-.000149,-.004997,
-.00044,-.00498,
-.000729,-.004946,
-.001015,-.004895,
-.00129,-.00483,
-.00044,-.00398,
90.*
4,1,15,.00398,-.00044,
.003999,-.000208,
.004004,.000025,
.003996,.000258,
.00398,.00044,
.00483,.00129,
.004897,.001007,
.004947,.000721,
.004981,.000432,
.004997,.000141,
.004997,-.000149,
.00498,-.00044,
.004946,-.000729,
.004895,-.001015,
.00483,-.00129,
.00398,-.00044,
90.*
4,1,15,.00044,.00398,
.000208,.003999,
-.000025,.004004,
-.000258,.003996,
-.00044,.00398,
-.00129,.00483,
-.001007,.004897,
-.000721,.004947,
-.000432,.004981,
-.000141,.004997,
.000149,.004997,
.00044,.00498,
.000729,.004946,
.001015,.004895,
.00129,.00483,
.00044,.00398,
90.*
%
%ADD36MACRO36*%
%AMMACRO16*
4,1,15,.00398,.00044,
.003999,.000208,
.004004,-.000025,
.003996,-.000258,
.00398,-.00044,
.00483,-.00129,
.004897,-.001007,
.004947,-.000721,
.004981,-.000432,
.004997,-.000141,
.004997,.000149,
.00498,.00044,
.004946,.000729,
.004895,.001015,
.00483,.00129,
.00398,.00044,
0.0*
4,1,15,.00044,-.00398,
.000208,-.003999,
-.000025,-.004004,
-.000258,-.003996,
-.00044,-.00398,
-.00129,-.00483,
-.001007,-.004897,
-.000721,-.004947,
-.000432,-.004981,
-.000141,-.004997,
.000149,-.004997,
.00044,-.00498,
.000729,-.004946,
.001015,-.004895,
.00129,-.00483,
.00044,-.00398,
0.0*
4,1,15,-.00398,-.00044,
-.003999,-.000208,
-.004004,.000025,
-.003996,.000258,
-.00398,.00044,
-.00483,.00129,
-.004897,.001007,
-.004947,.000721,
-.004981,.000432,
-.004997,.000141,
-.004997,-.000149,
-.00498,-.00044,
-.004946,-.000729,
-.004895,-.001015,
-.00483,-.00129,
-.00398,-.00044,
0.0*
4,1,15,-.00044,.00398,
-.000208,.003999,
.000025,.004004,
.000258,.003996,
.00044,.00398,
.00129,.00483,
.001007,.004897,
.000721,.004947,
.000432,.004981,
.000141,.004997,
-.000149,.004997,
-.00044,.00498,
-.000729,.004946,
-.001015,.004895,
-.00129,.00483,
-.00044,.00398,
0.0*
%
%ADD16MACRO16*%
%AMMACRO37*
4,1,47,.19499,.0719,
.215281,.036007,
.229031,-.002865,
.235822,-.043533,
.235448,-.084763,
.22792,-.125302,
.213467,-.163917,
.192528,-.199436,
.16574,-.23078,
.133915,-.256995,
.098022,-.277286,
.059151,-.291036,
.018482,-.297827,
-.022748,-.297453,
-.063286,-.289925,
-.101902,-.275472,
-.137421,-.254533,
-.168764,-.227745,
-.19498,-.19592,
-.215271,-.160027,
-.229021,-.121156,
-.235812,-.080487,
-.235438,-.039257,
-.22791,.001281,
-.213457,.039897,
-.19498,.0719,
-.17079,.109417,
-.148822,.148276,
-.129151,.188348,
-.11538,.22052,
-.105587,.239854,
-.092586,.257193,
-.076771,.272012,
-.058623,.283859,
-.038693,.292375,
-.017588,.297301,
.004052,.298487,
.025569,.295897,
.04631,.28961,
.065644,.279817,
.082983,.266816,
.097802,.251001,
.109649,.232853,
.1154,.22052,
.133222,.179593,
.153393,.139771,
.175846,.101189,
.19499,.0719,
0.0*
%
%ADD37MACRO37*%
%AMMACRO24*
4,1,15,-.00398,.00044,
-.003999,.000208,
-.004004,-.000025,
-.003996,-.000258,
-.00398,-.00044,
-.00483,-.00129,
-.004897,-.001007,
-.004947,-.000721,
-.004981,-.000432,
-.004997,-.000141,
-.004997,.000149,
-.00498,.00044,
-.004946,.000729,
-.004895,.001015,
-.00483,.00129,
-.00398,.00044,
0.0*
4,1,15,-.00044,-.00398,
-.000208,-.003999,
.000025,-.004004,
.000258,-.003996,
.00044,-.00398,
.00129,-.00483,
.001007,-.004897,
.000721,-.004947,
.000432,-.004981,
.000141,-.004997,
-.000149,-.004997,
-.00044,-.00498,
-.000729,-.004946,
-.001015,-.004895,
-.00129,-.00483,
-.00044,-.00398,
0.0*
4,1,15,.00398,-.00044,
.003999,-.000208,
.004004,.000025,
.003996,.000258,
.00398,.00044,
.00483,.00129,
.004897,.001007,
.004947,.000721,
.004981,.000432,
.004997,.000141,
.004997,-.000149,
.00498,-.00044,
.004946,-.000729,
.004895,-.001015,
.00483,-.00129,
.00398,-.00044,
0.0*
4,1,15,.00044,.00398,
.000208,.003999,
-.000025,.004004,
-.000258,.003996,
-.00044,.00398,
-.00129,.00483,
-.001007,.004897,
-.000721,.004947,
-.000432,.004981,
-.000141,.004997,
.000149,.004997,
.00044,.00498,
.000729,.004946,
.001015,.004895,
.00129,.00483,
.00044,.00398,
0.0*
%
%ADD24MACRO24*%
%ADD39C,.121*%
%ADD31C,.122*%
%ADD15C,.114*%
%ADD19C,.115*%
%ADD13O,.206X.285*%
%ADD32C,.125*%
%ADD10C,.206*%
%ADD33C,.432*%
%ADD25C,.18*%
%ADD14C,.208*%
%ADD40O,.159X.237*%
%ADD26C,.139*%
%ADD18C,.265*%
%ADD41C,.159*%
%ADD43C,.178*%
%AMMACRO35*
4,1,15,.00398,.00044,
.003999,.000208,
.004004,-.000025,
.003996,-.000258,
.00398,-.00044,
.00483,-.00129,
.004897,-.001007,
.004947,-.000721,
.004981,-.000432,
.004997,-.000141,
.004997,.000149,
.00498,.00044,
.004946,.000729,
.004895,.001015,
.00483,.00129,
.00398,.00044,
180.*
4,1,15,.00044,-.00398,
.000208,-.003999,
-.000025,-.004004,
-.000258,-.003996,
-.00044,-.00398,
-.00129,-.00483,
-.001007,-.004897,
-.000721,-.004947,
-.000432,-.004981,
-.000141,-.004997,
.000149,-.004997,
.00044,-.00498,
.000729,-.004946,
.001015,-.004895,
.00129,-.00483,
.00044,-.00398,
180.*
4,1,15,-.00398,-.00044,
-.003999,-.000208,
-.004004,.000025,
-.003996,.000258,
-.00398,.00044,
-.00483,.00129,
-.004897,.001007,
-.004947,.000721,
-.004981,.000432,
-.004997,.000141,
-.004997,-.000149,
-.00498,-.00044,
-.004946,-.000729,
-.004895,-.001015,
-.00483,-.00129,
-.00398,-.00044,
180.*
4,1,15,-.00044,.00398,
-.000208,.003999,
.000025,.004004,
.000258,.003996,
.00044,.00398,
.00129,.00483,
.001007,.004897,
.000721,.004947,
.000432,.004981,
.000141,.004997,
-.000149,.004997,
-.00044,.00498,
-.000729,.004946,
-.001015,.004895,
-.00129,.00483,
-.00044,.00398,
180.*
%
%ADD35MACRO35*%
%AMMACRO17*
4,1,15,.00398,.00044,
.003999,.000208,
.004004,-.000025,
.003996,-.000258,
.00398,-.00044,
.00483,-.00129,
.004897,-.001007,
.004947,-.000721,
.004981,-.000432,
.004997,-.000141,
.004997,.000149,
.00498,.00044,
.004946,.000729,
.004895,.001015,
.00483,.00129,
.00398,.00044,
270.*
4,1,15,.00044,-.00398,
.000208,-.003999,
-.000025,-.004004,
-.000258,-.003996,
-.00044,-.00398,
-.00129,-.00483,
-.001007,-.004897,
-.000721,-.004947,
-.000432,-.004981,
-.000141,-.004997,
.000149,-.004997,
.00044,-.00498,
.000729,-.004946,
.001015,-.004895,
.00129,-.00483,
.00044,-.00398,
270.*
4,1,15,-.00398,-.00044,
-.003999,-.000208,
-.004004,.000025,
-.003996,.000258,
-.00398,.00044,
-.00483,.00129,
-.004897,.001007,
-.004947,.000721,
-.004981,.000432,
-.004997,.000141,
-.004997,-.000149,
-.00498,-.00044,
-.004946,-.000729,
-.004895,-.001015,
-.00483,-.00129,
-.00398,-.00044,
270.*
4,1,15,-.00044,.00398,
-.000208,.003999,
.000025,.004004,
.000258,.003996,
.00044,.00398,
.00129,.00483,
.001007,.004897,
.000721,.004947,
.000432,.004981,
.000141,.004997,
-.000149,.004997,
-.00044,.00498,
-.000729,.004946,
-.001015,.004895,
-.00129,.00483,
-.00044,.00398,
270.*
%
%ADD17MACRO17*%
%AMMACRO29*
4,1,15,-.00398,.00044,
-.003999,.000208,
-.004004,-.000025,
-.003996,-.000258,
-.00398,-.00044,
-.00483,-.00129,
-.004897,-.001007,
-.004947,-.000721,
-.004981,-.000432,
-.004997,-.000141,
-.004997,.000149,
-.00498,.00044,
-.004946,.000729,
-.004895,.001015,
-.00483,.00129,
-.00398,.00044,
180.*
4,1,15,-.00044,-.00398,
-.000208,-.003999,
.000025,-.004004,
.000258,-.003996,
.00044,-.00398,
.00129,-.00483,
.001007,-.004897,
.000721,-.004947,
.000432,-.004981,
.000141,-.004997,
-.000149,-.004997,
-.00044,-.00498,
-.000729,-.004946,
-.001015,-.004895,
-.00129,-.00483,
-.00044,-.00398,
180.*
4,1,15,.00398,-.00044,
.003999,-.000208,
.004004,.000025,
.003996,.000258,
.00398,.00044,
.00483,.00129,
.004897,.001007,
.004947,.000721,
.004981,.000432,
.004997,.000141,
.004997,-.000149,
.00498,-.00044,
.004946,-.000729,
.004895,-.001015,
.00483,-.00129,
.00398,-.00044,
180.*
4,1,15,.00044,.00398,
.000208,.003999,
-.000025,.004004,
-.000258,.003996,
-.00044,.00398,
-.00129,.00483,
-.001007,.004897,
-.000721,.004947,
-.000432,.004981,
-.000141,.004997,
.000149,.004997,
.00044,.00498,
.000729,.004946,
.001015,.004895,
.00129,.00483,
.00044,.00398,
180.*
%
%ADD29MACRO29*%
%ADD44C,.02*%
%ADD45C,.006*%
%ADD51C,.06104*%
%ADD52C,.07704*%
%ADD53C,.11004*%
%ADD50C,.11104*%
%ADD57C,.11704*%
%ADD54C,.13504*%
%ADD56C,.11804*%
%ADD49C,.37504*%
%ADD62C,.23627*%
%ADD55C,.29531*%
%ADD48C,.29532*%
%ADD46O,.55202X.78802*%
%ADD61O,.09834X.04322*%
%ADD47O,.55204X.78804*%
%ADD60O,.09836X.04324*%
%ADD59O,.09854X.04342*%
%ADD58O,.09856X.04344*%
G75*
%LPD*%
G75*
G36*
G01X-6000Y-158756D02*
X1940843D01*
Y1664268D01*
X-6000D01*
Y-158756D01*
G37*
%LPC*%
G75*
G36*
G01X755787Y1463504D02*
X783465D01*
G03X792402Y1472441I0J8937D01*
G01Y1653268D01*
X956030D01*
Y1572461D01*
X961350Y1567141D01*
X987898D01*
X992550Y1562489D01*
Y1488789D01*
X993395Y1487944D01*
G03X994134Y1487205I2388J1649D01*
G01X995589Y1485750D01*
X1080011D01*
X1082050Y1487789D01*
Y1492066D01*
G03Y1492135I-751J34D01*
G01Y1534611D01*
X1079512Y1537149D01*
Y1555189D01*
X1084250Y1559927D01*
Y1577311D01*
X1079512Y1582049D01*
Y1650584D01*
G03X1080699Y1652855I-1414J2185D01*
G02X1081098Y1653268I400J13D01*
G01X1215472D01*
Y1477441D01*
X1168110D01*
G03X1159173Y1468504I0J-8937D01*
G01Y1421808D01*
X1150181D01*
G03X1145619I-2281J-308D01*
G01X1084385D01*
X1080952Y1418374D01*
Y1148882D01*
X1085158Y1144676D01*
X1145553D01*
X1149758Y1148880D01*
Y1367978D01*
X1156199Y1374419D01*
G03X1160553Y1373969I2474J2648D01*
G03X1168110Y1369803I7557J4771D01*
G01X1929843D01*
Y5000D01*
X1564055D01*
Y55118D01*
G03X1559646Y62823I-8937J0D01*
G01Y140921D01*
X1555550Y145018D01*
X1375723D01*
X1371574Y140869D01*
Y65851D01*
G03X1371356Y63650I2426J-1352D01*
G03X1365079Y55118I2660J-8532D01*
G01Y5000D01*
X1185039D01*
G03X1176102Y-3937I0J-8937D01*
G01Y-147756D01*
X871142D01*
Y-11811D01*
G03X862205Y-2874I-8937J0D01*
G01X847835D01*
X847784Y-2751D01*
G03X843538I-2123J-891D01*
G01X843487Y-2874D01*
X835982D01*
X835941Y-2728D01*
G03X831507I-2217J-618D01*
G01X831466Y-2874D01*
X792341D01*
X792317Y-2702D01*
G03X783466Y5000I-8852J-1235D01*
G01X595551D01*
Y55119D01*
G03X591664Y62492I-8937J0D01*
G03X591142Y66187I-2664J1508D01*
G01Y140921D01*
X587046Y145018D01*
X527577D01*
X522944Y140384D01*
Y99975D01*
X521546Y98578D01*
G03X520325Y98032I304J-2318D01*
G01X518266D01*
X515050Y94815D01*
G03X512949Y94054I-286J-2492D01*
G01X498571D01*
X494412Y98214D01*
G02X494759Y98891I283J282D01*
G03X494118Y122089I1894J11660D01*
G02X493632Y122480I-86J391D01*
G01Y140360D01*
X488975Y145018D01*
X478557D01*
G03X474081I-2238J-537D01*
G01X407219D01*
X403070Y140869D01*
Y63715D01*
G03X396575Y55118I2442J-8597D01*
G01Y5000D01*
X5000D01*
Y10045D01*
G02X5657Y10351I400J0D01*
G03X29922Y21653I9500J11303D01*
G01Y21654D01*
G03X5657Y32956I-14765J-1D01*
G02X5000Y33262I-257J306D01*
G01Y462753D01*
G02X5657Y463059I400J-1D01*
G03X12306Y459885I9500J11350D01*
G03X18008I2851J10574D01*
G03Y488933I-2851J14524D01*
G03X12306I-2851J-10574D01*
G03X5657Y485759I2851J-14524D01*
G02X5000Y486065I-257J307D01*
G01Y1369803D01*
X746850D01*
G03X755787Y1378740I0J8937D01*
G01Y1463504D01*
G37*
G36*
G01X524529Y95902D02*
X526945Y98318D01*
Y138727D01*
X529234Y141016D01*
X585389D01*
X587141Y139264D01*
Y65821D01*
G03X586409Y64237I1859J-1820D01*
G01X586392Y64055D01*
X559990D01*
X559973Y64236D01*
G03X558860Y66171I-2690J-259D01*
G02X558811Y66778I234J324D01*
G03X559444Y68306I-1528J1528D01*
G01Y73819D01*
G03X555122I-2161J0D01*
G01Y68307D01*
G03X555755Y66778I2161J-1D01*
G02X555706Y66171I-283J-283D01*
G03X554593Y64236I1577J-2194D01*
G01X554576Y64055D01*
X545817D01*
X545800Y64236D01*
G03X544687Y66171I-2690J-259D01*
G02X544638Y66778I234J324D01*
G03X545272Y68306I-1528J1529D01*
G01Y73819D01*
G03X540948I-2162J0D01*
G01Y68307D01*
G03X541582Y66778I2161J0D01*
G02X541533Y66171I-283J-283D01*
G03X540420Y64236I1577J-2194D01*
G01X540403Y64055D01*
X531644D01*
X531627Y64236D01*
G03X530514Y66171I-2690J-259D01*
G02X530465Y66778I234J324D01*
G03X531098Y68306I-1528J1528D01*
G01Y73819D01*
G03X526776I-2161J0D01*
G01Y68307D01*
G03X527409Y66778I2161J-1D01*
G02X527360Y66171I-283J-283D01*
G03X526247Y64236I1577J-2194D01*
G01X526230Y64055D01*
X517471D01*
X517454Y64236D01*
G03X516341Y66171I-2690J-259D01*
G02X516292Y66778I234J324D01*
G03X516926Y68306I-1528J1529D01*
G01Y73819D01*
G03X512602I-2162J0D01*
G01Y68307D01*
G03X513236Y66778I2161J0D01*
G02X513187Y66171I-283J-283D01*
G03X512074Y64236I1577J-2194D01*
G01X512057Y64055D01*
X474951D01*
X474934Y64236D01*
G03X473821Y66171I-2690J-259D01*
G02X473772Y66778I234J324D01*
G03X474406Y68306I-1528J1529D01*
G01Y73819D01*
G03X470082I-2162J0D01*
G01Y68307D01*
G03X470716Y66778I2161J0D01*
G02X470667Y66171I-283J-283D01*
G03X469554Y64236I1577J-2194D01*
G01X469537Y64055D01*
X460778D01*
X460761Y64236D01*
G03X459648Y66171I-2690J-259D01*
G02X459599Y66778I234J324D01*
G03X460232Y68306I-1528J1528D01*
G01Y73819D01*
G03X455910I-2161J0D01*
G01Y68307D01*
G03X456543Y66778I2161J-1D01*
G02X456494Y66171I-283J-283D01*
G03X455381Y64236I1577J-2194D01*
G01X455364Y64055D01*
X446605D01*
X446588Y64236D01*
G03X445475Y66171I-2690J-259D01*
G02X445426Y66778I234J324D01*
G03X446060Y68306I-1528J1529D01*
G01Y73819D01*
G03X441736I-2162J0D01*
G01Y68307D01*
G03X442370Y66778I2161J0D01*
G02X442321Y66171I-283J-283D01*
G03X441208Y64236I1577J-2194D01*
G01X441191Y64055D01*
X432431D01*
X432414Y64236D01*
G03X431301Y66171I-2690J-259D01*
G02X431252Y66778I234J324D01*
G03X431886Y68306I-1528J1529D01*
G01Y73819D01*
G03X427562I-2162J0D01*
G01Y68307D01*
G03X428196Y66778I2161J0D01*
G02X428147Y66171I-283J-283D01*
G03X427034Y64236I1577J-2194D01*
G01X427017Y64055D01*
X407072D01*
Y139212D01*
X408876Y141016D01*
X487318D01*
X489631Y138703D01*
Y120050D01*
G03Y101052I7023J-9499D01*
G01Y97336D01*
X496914Y90053D01*
X513298D01*
G03X513382Y90001I1464J2271D01*
G02X513405Y89674I-103J-172D01*
G03X512602Y87993I1358J-1681D01*
G01Y82481D01*
G03X516926Y82480I2162J0D01*
G01Y87993D01*
G03X516292Y89522I-2161J0D01*
G02X516341Y90129I283J283D01*
G03X517295Y91376I-1577J2195D01*
G01X517310Y91417D01*
X519923Y94030D01*
X520323D01*
X520373Y93997D01*
G03X520468Y93938I1473J2266D01*
G02X520491Y93611I-103J-172D01*
G03X519688Y91930I1358J-1681D01*
G01Y86418D01*
G03X524012Y86417I2162J0D01*
G01Y91930D01*
G03X523378Y93459I-2161J0D01*
G02X523427Y94066I283J283D01*
G03X524519Y95838I-1577J2194D01*
G01X524529Y95902D01*
G37*
G36*
G01X1075497Y1652855D02*
G03X1077832Y1650180I2601J-87D01*
G01X1078012Y1650161D01*
Y1581427D01*
X1082750Y1576689D01*
Y1560549D01*
X1078012Y1555811D01*
Y1539402D01*
X1076360Y1537750D01*
X996299D01*
X996295Y1537754D01*
X996163D01*
X994050Y1539867D01*
Y1563111D01*
X988520Y1568641D01*
X961972D01*
X957530Y1573083D01*
Y1653268D01*
X1075098D01*
G02X1075497Y1652855I-1J-400D01*
G37*
G36*
G01X1080550Y1488411D02*
X1079389Y1487250D01*
X996211D01*
X994050Y1489411D01*
Y1534335D01*
X995965Y1536250D01*
X1078289D01*
X1080550Y1533989D01*
Y1492168D01*
X1080549Y1492161D01*
G03Y1492040I750J-61D01*
G01X1080550Y1492033D01*
Y1488411D01*
G37*
G36*
G01X1159173Y1417806D02*
Y1380067D01*
G02X1158760Y1379668I-400J1D01*
G03X1157758Y1379503I-86J-2601D01*
G01X1157724Y1379490D01*
X1155611D01*
X1145756Y1369635D01*
Y1150537D01*
X1143896Y1148677D01*
X1086815D01*
X1084953Y1150539D01*
Y1416717D01*
X1086042Y1417806D01*
X1159173D01*
G37*
G36*
G01X1376602Y64461D02*
G03X1375576Y66570I-2602J38D01*
G01Y139212D01*
X1377380Y141016D01*
X1553893D01*
X1555645Y139264D01*
Y66721D01*
G03X1554398Y64461I1355J-2222D01*
G02X1553998Y64055I-400J-6D01*
G01X1528494D01*
X1528477Y64236D01*
G03X1527364Y66171I-2690J-259D01*
G02X1527315Y66778I234J324D01*
G03X1527948Y68306I-1528J1528D01*
G01Y73819D01*
G03X1523626I-2161J0D01*
G01Y68307D01*
G03X1524259Y66778I2161J-1D01*
G02X1524210Y66171I-283J-283D01*
G03X1523097Y64236I1577J-2194D01*
G01X1523080Y64055D01*
X1514321D01*
X1514304Y64236D01*
G03X1513191Y66171I-2690J-259D01*
G02X1513142Y66778I234J324D01*
G03X1513776Y68306I-1528J1529D01*
G01Y73819D01*
G03X1509452I-2162J0D01*
G01Y68307D01*
G03X1510086Y66778I2161J0D01*
G02X1510037Y66171I-283J-283D01*
G03X1508924Y64236I1577J-2194D01*
G01X1508907Y64055D01*
X1500148D01*
X1500131Y64236D01*
G03X1499018Y66171I-2690J-259D01*
G02X1498969Y66778I234J324D01*
G03X1499602Y68306I-1528J1528D01*
G01Y73819D01*
G03X1495280I-2161J0D01*
G01Y68307D01*
G03X1495913Y66778I2161J-1D01*
G02X1495864Y66171I-283J-283D01*
G03X1494751Y64236I1577J-2194D01*
G01X1494734Y64055D01*
X1485975D01*
X1485958Y64236D01*
G03X1484845Y66171I-2690J-259D01*
G02X1484796Y66778I234J324D01*
G03X1485430Y68306I-1528J1529D01*
G01Y73819D01*
G03X1481106I-2162J0D01*
G01Y68307D01*
G03X1481740Y66778I2161J0D01*
G02X1481691Y66171I-283J-283D01*
G03X1480578Y64236I1577J-2194D01*
G01X1480561Y64055D01*
X1443455D01*
X1443438Y64236D01*
G03X1442325Y66171I-2690J-259D01*
G02X1442276Y66778I234J324D01*
G03X1442910Y68306I-1528J1529D01*
G01Y73819D01*
G03X1438586I-2162J0D01*
G01Y68307D01*
G03X1439220Y66778I2161J0D01*
G02X1439171Y66171I-283J-283D01*
G03X1438058Y64236I1577J-2194D01*
G01X1438041Y64055D01*
X1429282D01*
X1429265Y64236D01*
G03X1428152Y66171I-2690J-259D01*
G02X1428103Y66778I234J324D01*
G03X1428736Y68306I-1528J1528D01*
G01Y73819D01*
G03X1424414I-2161J0D01*
G01Y68307D01*
G03X1425047Y66778I2161J-1D01*
G02X1424998Y66171I-283J-283D01*
G03X1423885Y64236I1577J-2194D01*
G01X1423868Y64055D01*
X1415109D01*
X1415092Y64236D01*
G03X1413979Y66171I-2690J-259D01*
G02X1413930Y66778I234J324D01*
G03X1414564Y68306I-1528J1529D01*
G01Y73819D01*
G03X1410240I-2162J0D01*
G01Y68307D01*
G03X1410874Y66778I2161J0D01*
G02X1410825Y66171I-283J-283D01*
G03X1409712Y64236I1577J-2194D01*
G01X1409695Y64055D01*
X1400935D01*
X1400918Y64236D01*
G03X1399805Y66171I-2690J-259D01*
G02X1399756Y66778I234J324D01*
G03X1400390Y68306I-1528J1529D01*
G01Y73819D01*
G03X1396066I-2162J0D01*
G01Y68307D01*
G03X1396700Y66778I2161J0D01*
G02X1396651Y66171I-283J-283D01*
G03X1395538Y64236I1577J-2194D01*
G01X1395521Y64055D01*
X1377002D01*
G02X1376602Y64461I0J400D01*
G37*
%LPD*%
G75*
G36*
G01X1897508Y459879D02*
G02X1891860I-2824J10580D01*
G02Y488939I2824J14530D01*
G02X1897508I2824J-10580D01*
G02Y459879I-2824J-14530D01*
G37*
G36*
G01X907745Y-40121D02*
G02X902097I-2824J10580D01*
G02Y-11061I2824J14530D01*
G02X907745I2824J-10580D01*
G02Y-40121I-2824J-14530D01*
G37*
G36*
G01X1404234Y190242D02*
Y185741D01*
G02X1401192Y185742I-1521J1D01*
G01Y190242D01*
G02X1404234I1521J0D01*
G37*
G36*
G01X1385463Y166302D02*
X1380962D01*
G02X1380963Y169344I1J1521D01*
G01X1385463D01*
G02Y166302I0J-1521D01*
G37*
G36*
G01X1261462Y1080754D02*
Y1076253D01*
G02X1258138Y1076254I-1662J1D01*
G01Y1080754D01*
G02X1261462I1662J0D01*
G37*
G36*
G01X1075250Y1413872D02*
X1070749D01*
G02X1070750Y1416876I1J1502D01*
G01X1075250D01*
G02Y1413872I0J-1502D01*
G37*
G36*
G01Y1406786D02*
X1070749D01*
G02X1070750Y1409788I1J1501D01*
G01X1075250D01*
G02Y1406786I0J-1501D01*
G37*
G36*
G01Y1399700D02*
X1070749D01*
G02X1070750Y1402702I1J1501D01*
G01X1075250D01*
G02Y1399700I0J-1501D01*
G37*
G36*
G01Y1392612D02*
X1070749D01*
G02X1070750Y1395616I1J1502D01*
G01X1075250D01*
G02Y1392612I0J-1502D01*
G37*
G36*
G01Y1385526D02*
X1070749D01*
G02X1070750Y1388530I1J1502D01*
G01X1075250D01*
G02Y1385526I0J-1502D01*
G37*
G36*
G01Y1378440D02*
X1070749D01*
G02X1070750Y1381442I1J1501D01*
G01X1075250D01*
G02Y1378440I0J-1501D01*
G37*
G36*
G01Y1328824D02*
X1070749D01*
G02X1070750Y1331846I1J1511D01*
G01X1075250D01*
G02Y1328824I0J-1511D01*
G37*
G36*
G01Y1293390D02*
X1070749D01*
G02X1070750Y1296414I1J1512D01*
G01X1075250D01*
G02Y1293390I0J-1512D01*
G37*
G36*
G01Y1300476D02*
X1070749D01*
G02X1070750Y1303500I1J1512D01*
G01X1075250D01*
G02Y1300476I0J-1512D01*
G37*
G36*
G01Y1307564D02*
X1070749D01*
G02X1070750Y1310586I1J1511D01*
G01X1075250D01*
G02Y1307564I0J-1511D01*
G37*
G36*
G01Y1314650D02*
X1070749D01*
G02X1070750Y1317672I1J1511D01*
G01X1075250D01*
G02Y1314650I0J-1511D01*
G37*
G36*
G01Y1321736D02*
X1070749D01*
G02X1070750Y1324760I1J1512D01*
G01X1075250D01*
G02Y1321736I0J-1512D01*
G37*
G36*
G01Y1229610D02*
X1070749D01*
G02X1070750Y1232634I1J1512D01*
G01X1075250D01*
G02Y1229610I0J-1512D01*
G37*
G36*
G01Y1236698D02*
X1070749D01*
G02X1070750Y1239720I1J1511D01*
G01X1075250D01*
G02Y1236698I0J-1511D01*
G37*
G36*
G01Y1243784D02*
X1070749D01*
G02X1070750Y1246806I1J1511D01*
G01X1075250D01*
G02Y1243784I0J-1511D01*
G37*
G36*
G01Y1208350D02*
X1070749D01*
G02X1070750Y1211374I1J1512D01*
G01X1075250D01*
G02Y1208350I0J-1512D01*
G37*
G36*
G01Y1215438D02*
X1070749D01*
G02X1070750Y1218460I1J1511D01*
G01X1075250D01*
G02Y1215438I0J-1511D01*
G37*
G36*
G01Y1222524D02*
X1070749D01*
G02X1070750Y1225546I1J1511D01*
G01X1075250D01*
G02Y1222524I0J-1511D01*
G37*
G36*
G01X1088954Y1052852D02*
X1145627D01*
X1149834Y1048645D01*
Y981399D01*
X1144668Y976234D01*
X1079396D01*
X1075192Y980438D01*
Y1039089D01*
X1088954Y1052852D01*
G37*
G36*
G01X878540Y1646457D02*
Y1640944D01*
G02X874216Y1640945I-2162J1D01*
G01Y1646457D01*
G02X878540I2162J0D01*
G37*
G36*
G01X871454Y1636221D02*
Y1630708D01*
G02X867130Y1630709I-2162J1D01*
G01Y1636221D01*
G02X871454I2162J0D01*
G37*
G36*
G01X864366Y1646457D02*
Y1640944D01*
G02X860044Y1640945I-2161J1D01*
G01Y1646457D01*
G02X864366I2161J0D01*
G37*
G36*
G01X857280Y1636221D02*
Y1630708D01*
G02X852956Y1630709I-2162J1D01*
G01Y1636221D01*
G02X857280I2162J0D01*
G37*
G36*
G01X850194Y1646457D02*
Y1640944D01*
G02X845870Y1640945I-2162J1D01*
G01Y1646457D01*
G02X850194I2162J0D01*
G37*
G36*
G01X878540Y1603937D02*
Y1598424D01*
G02X874216Y1598425I-2162J1D01*
G01Y1603937D01*
G02X878540I2162J0D01*
G37*
G36*
G01X871454Y1607874D02*
Y1602362D01*
G02X867130Y1602363I-2162J1D01*
G01Y1607874D01*
G02X871454I2162J0D01*
G37*
G36*
G01X864366Y1603937D02*
Y1598424D01*
G02X860044Y1598425I-2161J1D01*
G01Y1603937D01*
G02X864366I2161J0D01*
G37*
G36*
G01X857280Y1607874D02*
Y1602362D01*
G02X852956Y1602363I-2162J1D01*
G01Y1607874D01*
G02X857280I2162J0D01*
G37*
G36*
G01X850194Y1603937D02*
Y1598424D01*
G02X845870Y1598425I-2162J1D01*
G01Y1603937D01*
G02X850194I2162J0D01*
G37*
G36*
G01X843106Y1636221D02*
Y1630708D01*
G02X838784Y1630709I-2161J1D01*
G01Y1636221D01*
G02X843106I2161J0D01*
G37*
G36*
G01X836020Y1646457D02*
Y1640944D01*
G02X831698Y1640945I-2161J1D01*
G01Y1646457D01*
G02X836020I2161J0D01*
G37*
G36*
G01X828934Y1636221D02*
Y1630708D01*
G02X824610Y1630709I-2162J1D01*
G01Y1636221D01*
G02X828934I2162J0D01*
G37*
G36*
G01Y1622048D02*
Y1616535D01*
G02X824610Y1616536I-2162J1D01*
G01Y1622048D01*
G02X828934I2162J0D01*
G37*
G36*
G01X843106Y1607874D02*
Y1602362D01*
G02X838784Y1602363I-2161J1D01*
G01Y1607874D01*
G02X843106I2161J0D01*
G37*
G36*
G01X836020Y1603937D02*
Y1598424D01*
G02X831698Y1598425I-2161J1D01*
G01Y1603937D01*
G02X836020I2161J0D01*
G37*
G36*
G01X828934Y1607874D02*
Y1602362D01*
G02X824610Y1602363I-2162J1D01*
G01Y1607874D01*
G02X828934I2162J0D01*
G37*
G36*
G01X1898061Y1091290D02*
X1898062Y1091293D01*
Y1095715D01*
X1898061Y1095718D01*
G02X1901065I1502J36D01*
G01X1901064Y1095715D01*
Y1091293D01*
X1901065Y1091290D01*
G02X1898061I-1502J-36D01*
G37*
G36*
G01X1776852Y1095718D02*
Y1091290D01*
G02X1773848I-1502J-36D01*
G01Y1095718D01*
G02X1776852I1502J36D01*
G37*
G36*
G01X1652640D02*
Y1091290D01*
G02X1649636I-1502J-36D01*
G01Y1095718D01*
G02X1652640I1502J36D01*
G37*
G36*
G01X1525423Y1091290D02*
X1525424Y1091293D01*
Y1095715D01*
X1525423Y1095718D01*
G02X1528427I1502J36D01*
G01X1528426Y1095715D01*
Y1091293D01*
X1528427Y1091290D01*
G02X1525423I-1502J-36D01*
G37*
G36*
G01X1401211D02*
X1401212Y1091293D01*
Y1095715D01*
X1401211Y1095718D01*
G02X1404215I1502J36D01*
G01X1404214Y1095715D01*
Y1091293D01*
X1404215Y1091290D01*
G02X1401211I-1502J-36D01*
G37*
G36*
G01X1280002Y1095718D02*
Y1091290D01*
G02X1276998I-1502J-36D01*
G01Y1095718D01*
G02X1280002I1502J36D01*
G37*
G36*
G01X747549Y1091290D02*
X747550Y1091293D01*
Y1095715D01*
X747549Y1095718D01*
G02X750553I1502J36D01*
G01X750552Y1095715D01*
Y1091293D01*
X750553Y1091290D01*
G02X747549I-1502J-36D01*
G37*
G36*
G01X626340Y1095718D02*
Y1091290D01*
G02X623336I-1502J-36D01*
G01Y1095718D01*
G02X626340I1502J36D01*
G37*
G36*
G01X499123Y1091290D02*
X499124Y1091293D01*
Y1095715D01*
X499123Y1095718D01*
G02X502127I1502J36D01*
G01X502126Y1095715D01*
Y1091293D01*
X502127Y1091290D01*
G02X499123I-1502J-36D01*
G37*
G36*
G01X374911D02*
X374912Y1091293D01*
Y1095715D01*
X374911Y1095718D01*
G02X377915I1502J36D01*
G01X377914Y1095715D01*
Y1091293D01*
X377915Y1091290D01*
G02X374911I-1502J-36D01*
G37*
G36*
G01X253702Y1095718D02*
Y1091290D01*
G02X250698I-1502J-36D01*
G01Y1095718D01*
G02X253702I1502J36D01*
G37*
G36*
G01X129490D02*
Y1091290D01*
G02X126486I-1502J-36D01*
G01Y1095718D01*
G02X129490I1502J36D01*
G37*
G36*
G01X1879361Y1076290D02*
X1879362Y1076293D01*
Y1080715D01*
X1879361Y1080718D01*
G02X1882365I1502J36D01*
G01X1882364Y1080715D01*
Y1076293D01*
X1882365Y1076290D01*
G02X1879361I-1502J-36D01*
G37*
G36*
G01X1758152Y1080718D02*
Y1076290D01*
G02X1755148I-1502J-36D01*
G01Y1080718D01*
G02X1758152I1502J36D01*
G37*
G36*
G01X1633940D02*
Y1076290D01*
G02X1630936I-1502J-36D01*
G01Y1080718D01*
G02X1633940I1502J36D01*
G37*
G36*
G01X1506723Y1076290D02*
X1506724Y1076293D01*
Y1080715D01*
X1506723Y1080718D01*
G02X1509727I1502J36D01*
G01X1509726Y1080715D01*
Y1076293D01*
X1509727Y1076290D01*
G02X1506723I-1502J-36D01*
G37*
G36*
G01X1382511D02*
X1382512Y1076293D01*
Y1080715D01*
X1382511Y1080718D01*
G02X1385515I1502J36D01*
G01X1385514Y1080715D01*
Y1076293D01*
X1385515Y1076290D01*
G02X1382511I-1502J-36D01*
G37*
G36*
G01X1898061Y638534D02*
X1898062Y638537D01*
Y642959D01*
X1898061Y642962D01*
G02X1901065I1502J36D01*
G01X1901064Y642959D01*
Y638537D01*
X1901065Y638534D01*
G02X1898061I-1502J-36D01*
G37*
G36*
G01X1726852Y642962D02*
Y638534D01*
G02X1723848I-1502J-36D01*
G01Y642962D01*
G02X1726852I1502J36D01*
G37*
G36*
G01X1652640D02*
Y638534D01*
G02X1649636I-1502J-36D01*
G01Y642962D01*
G02X1652640I1502J36D01*
G37*
G36*
G01X1525423Y638534D02*
X1525424Y638537D01*
Y642959D01*
X1525423Y642962D01*
G02X1528427I1502J36D01*
G01X1528426Y642959D01*
Y638537D01*
X1528427Y638534D01*
G02X1525423I-1502J-36D01*
G37*
G36*
G01X1401211D02*
X1401212Y638537D01*
Y642959D01*
X1401211Y642962D01*
G02X1404215I1502J36D01*
G01X1404214Y642959D01*
Y638537D01*
X1404215Y638534D01*
G02X1401211I-1502J-36D01*
G37*
G36*
G01X1280002Y642962D02*
Y638534D01*
G02X1276998I-1502J-36D01*
G01Y642962D01*
G02X1280002I1502J36D01*
G37*
G36*
G01X747549Y638534D02*
X747550Y638537D01*
Y642959D01*
X747549Y642962D01*
G02X750553I1502J36D01*
G01X750552Y642959D01*
Y638537D01*
X750553Y638534D01*
G02X747549I-1502J-36D01*
G37*
G36*
G01X626340Y642962D02*
Y638534D01*
G02X623336I-1502J-36D01*
G01Y642962D01*
G02X626340I1502J36D01*
G37*
G36*
G01X499123Y638534D02*
X499124Y638537D01*
Y642959D01*
X499123Y642962D01*
G02X502127I1502J36D01*
G01X502126Y642959D01*
Y638537D01*
X502127Y638534D01*
G02X499123I-1502J-36D01*
G37*
G36*
G01X374911D02*
X374912Y638537D01*
Y642959D01*
X374911Y642962D01*
G02X377915I1502J36D01*
G01X377914Y642959D01*
Y638537D01*
X377915Y638534D01*
G02X374911I-1502J-36D01*
G37*
G36*
G01X253702Y642962D02*
Y638534D01*
G02X250698I-1502J-36D01*
G01Y642962D01*
G02X253702I1502J36D01*
G37*
G36*
G01X129490D02*
Y638534D01*
G02X126486I-1502J-36D01*
G01Y642962D01*
G02X129490I1502J36D01*
G37*
G36*
G01X1879361Y623534D02*
X1879362Y623537D01*
Y627959D01*
X1879361Y627962D01*
G02X1882365I1502J36D01*
G01X1882364Y627959D01*
Y623537D01*
X1882365Y623534D01*
G02X1879361I-1502J-36D01*
G37*
G36*
G01X1733152Y627962D02*
Y623534D01*
G02X1730148I-1502J-36D01*
G01Y627962D01*
G02X1733152I1502J36D01*
G37*
G36*
G01X1633940D02*
Y623534D01*
G02X1630936I-1502J-36D01*
G01Y627962D01*
G02X1633940I1502J36D01*
G37*
G36*
G01X1506723Y623534D02*
X1506724Y623537D01*
Y627959D01*
X1506723Y627962D01*
G02X1509727I1502J36D01*
G01X1509726Y627959D01*
Y623537D01*
X1509727Y623534D01*
G02X1506723I-1502J-36D01*
G37*
G36*
G01X1382511D02*
X1382512Y623537D01*
Y627959D01*
X1382511Y627962D01*
G02X1385515I1502J36D01*
G01X1385514Y627959D01*
Y623537D01*
X1385515Y623534D01*
G02X1382511I-1502J-36D01*
G37*
G36*
G01X1261302Y627962D02*
Y623534D01*
G02X1258298I-1502J-36D01*
G01Y627962D01*
G02X1261302I1502J36D01*
G37*
G36*
G01X1898061Y185778D02*
X1898062Y185781D01*
Y190203D01*
X1898061Y190206D01*
G02X1901065I1502J36D01*
G01X1901064Y190203D01*
Y185781D01*
X1901065Y185778D01*
G02X1898061I-1502J-36D01*
G37*
G36*
G01X1776852Y190206D02*
Y185778D01*
G02X1773848I-1502J-36D01*
G01Y190206D01*
G02X1776852I1502J36D01*
G37*
G36*
G01X1652640D02*
Y185778D01*
G02X1649636I-1502J-36D01*
G01Y190206D01*
G02X1652640I1502J36D01*
G37*
G36*
G01X1525423Y185778D02*
X1525424Y185781D01*
Y190203D01*
X1525423Y190206D01*
G02X1528427I1502J36D01*
G01X1528426Y190203D01*
Y185781D01*
X1528427Y185778D01*
G02X1525423I-1502J-36D01*
G37*
G36*
G01X747549D02*
X747550Y185781D01*
Y190203D01*
X747549Y190206D01*
G02X750553I1502J36D01*
G01X750552Y190203D01*
Y185781D01*
X750553Y185778D01*
G02X747549I-1502J-36D01*
G37*
G36*
G01X626340Y190206D02*
Y185778D01*
G02X623336I-1502J-36D01*
G01Y190206D01*
G02X626340I1502J36D01*
G37*
G36*
G01X499123Y185778D02*
X499124Y185781D01*
Y190203D01*
X499123Y190206D01*
G02X502127I1502J36D01*
G01X502126Y190203D01*
Y185781D01*
X502127Y185778D01*
G02X499123I-1502J-36D01*
G37*
G36*
G01X374911D02*
X374912Y185781D01*
Y190203D01*
X374911Y190206D01*
G02X377915I1502J36D01*
G01X377914Y190203D01*
Y185781D01*
X377915Y185778D01*
G02X374911I-1502J-36D01*
G37*
G36*
G01X253702Y190206D02*
Y185778D01*
G02X250698I-1502J-36D01*
G01Y190206D01*
G02X253702I1502J36D01*
G37*
G36*
G01X129490D02*
Y185778D01*
G02X126486I-1502J-36D01*
G01Y190206D01*
G02X129490I1502J36D01*
G37*
G36*
G01X1270436Y184325D02*
X1270439Y184324D01*
X1274861D01*
X1274864Y184325D01*
G02Y181321I36J-1502D01*
G01X1274861Y181322D01*
X1270439D01*
X1270436Y181321D01*
G02Y184325I-36J1502D01*
G37*
G36*
G01X1511414Y180198D02*
X1506986D01*
G02Y183202I-36J1502D01*
G01X1511414D01*
G02Y180198I36J-1502D01*
G37*
G36*
G01X1879361Y170778D02*
X1879362Y170781D01*
Y175203D01*
X1879361Y175206D01*
G02X1882365I1502J36D01*
G01X1882364Y175203D01*
Y170781D01*
X1882365Y170778D01*
G02X1879361I-1502J-36D01*
G37*
G36*
G01X1758152Y175206D02*
Y170778D01*
G02X1755148I-1502J-36D01*
G01Y175206D01*
G02X1758152I1502J36D01*
G37*
G36*
G01X1633940D02*
Y170778D01*
G02X1630936I-1502J-36D01*
G01Y175206D01*
G02X1633940I1502J36D01*
G37*
G36*
G01X1256786Y169325D02*
X1256789Y169324D01*
X1261211D01*
X1261214Y169325D01*
G02Y166321I36J-1502D01*
G01X1261211Y166322D01*
X1256789D01*
X1256786Y166321D01*
G02Y169325I-36J1502D01*
G37*
G36*
G01X720994Y464746D02*
X721150Y464781D01*
Y512880D01*
X715937Y518093D01*
X627587D01*
X624740Y520940D01*
Y538143D01*
X624737Y538161D01*
G02Y539001I2263J420D01*
G01X624740Y539019D01*
Y542471D01*
X624737Y542489D01*
G02Y543329I2263J420D01*
G01X624740Y543347D01*
Y613516D01*
X627858Y616634D01*
X685431D01*
X687214Y614851D01*
Y590534D01*
X690160Y587588D01*
X719779D01*
X721163Y588972D01*
Y613971D01*
X723826Y616634D01*
X825273D01*
X834150Y625511D01*
Y750211D01*
X863589Y779650D01*
X968811D01*
X982550Y765911D01*
Y578086D01*
G02Y551835I-6762J-13126D01*
G01Y3264D01*
X975328Y-3958D01*
X891915D01*
X886458Y1499D01*
X886378Y1501D01*
G02X884126Y3753I49J2301D01*
G01X884124Y3833D01*
X852814Y35143D01*
X852802Y35152D01*
G02X852336Y35618I1378J1844D01*
G01X852327Y35630D01*
X841550Y46407D01*
Y317689D01*
X819589Y339650D01*
X740089D01*
X721150Y358589D01*
Y460219D01*
X720994Y460254D01*
G02Y464746I506J2246D01*
G37*
G36*
G01X1034050Y94762D02*
Y760711D01*
X1053689Y780350D01*
X1157211D01*
X1171650Y765911D01*
Y731626D01*
G02X1171684Y729023I-1882J-1326D01*
G01X1171650Y728973D01*
Y728027D01*
X1171684Y727977D01*
G02Y725423I-1916J-1277D01*
G01X1171650Y725373D01*
Y724427D01*
X1171684Y724377D01*
G02X1171650Y721774I-1916J-1277D01*
G01Y689511D01*
X1284311Y576850D01*
X1335219D01*
X1335254Y577006D01*
G02X1339746I2246J-506D01*
G01X1339781Y576850D01*
X1383818D01*
X1391682Y568986D01*
Y482121D01*
X1378311Y468750D01*
X1285611D01*
X1169150Y352289D01*
Y-7711D01*
X1151311Y-25550D01*
X1049489D01*
X1034050Y-10111D01*
Y92324D01*
G02Y94762I1953J1219D01*
G37*
G36*
G01X970474Y-46450D02*
Y-70079D01*
G02X919290I-25592J0D01*
G01Y-46456D01*
G02X960345Y-26064I25592J0D01*
G03X960986Y-25741I241J319D01*
G02X970115Y-39262I14801J151D01*
G03X969576Y-39736I-153J-369D01*
G02X970474Y-46450I-24694J-6720D01*
G37*
G36*
G01X558368Y829921D02*
G02I-55120J0D01*
G37*
G36*
G01X1729038D02*
G02I-55121J0D01*
G37*
G36*
G01X533862Y91930D02*
G02X538186I2162J0D01*
G01Y86417D01*
G02X533862Y86418I-2162J1D01*
G01Y91930D01*
G37*
G36*
G01Y120276D02*
G02X538186I2162J0D01*
G01Y114763D01*
G02X533862Y114764I-2162J1D01*
G01Y120276D01*
G37*
G36*
G01X548036Y91930D02*
G02X552358I2161J0D01*
G01Y86417D01*
G02X548036Y86418I-2161J1D01*
G01Y91930D01*
G37*
G36*
G01X562208D02*
G02X566532I2162J0D01*
G01Y86417D01*
G02X562208Y86418I-2162J1D01*
G01Y91930D01*
G37*
G36*
G01Y120276D02*
G02X566532I2162J0D01*
G01Y114763D01*
G02X562208Y114764I-2162J1D01*
G01Y120276D01*
G37*
G36*
G01X526776Y87993D02*
G02X531098I2161J0D01*
G01Y82480D01*
G02X526776Y82481I-2161J1D01*
G01Y87993D01*
G37*
G36*
G01X533862Y77756D02*
G02X538186I2162J0D01*
G01Y72244D01*
G02X533862Y72245I-2162J1D01*
G01Y77756D01*
G37*
G36*
G01X540948Y87993D02*
G02X545272I2162J0D01*
G01Y82480D01*
G02X540948Y82481I-2162J1D01*
G01Y87993D01*
G37*
G36*
G01X555122D02*
G02X559444I2161J0D01*
G01Y82480D01*
G02X555122Y82481I-2161J1D01*
G01Y87993D01*
G37*
G36*
G01X548036Y77756D02*
G02X552358I2161J0D01*
G01Y72244D01*
G02X548036Y72245I-2161J1D01*
G01Y77756D01*
G37*
G36*
G01X562208D02*
G02X566532I2162J0D01*
G01Y72244D01*
G02X562208Y72245I-2162J1D01*
G01Y77756D01*
G37*
G36*
G01X477170Y91930D02*
G02X481492I2161J0D01*
G01Y86417D01*
G02X477170Y86418I-2161J1D01*
G01Y91930D01*
G37*
G36*
G01X481502Y114764D02*
G02X477160I-2171J0D01*
G01Y120277D01*
G02X481502Y120276I2171J-1D01*
G01Y114764D01*
G37*
G36*
G01X524012Y72245D02*
G02X519688I-2162J0D01*
G01Y77757D01*
G02X524012Y77756I2162J-1D01*
G01Y72245D01*
G37*
G36*
G01X477170Y77756D02*
G02X481492I2161J0D01*
G01Y72244D01*
G02X477170Y72245I-2161J1D01*
G01Y77756D01*
G37*
G36*
G01X434650Y91930D02*
G02X438972I2161J0D01*
G01Y86417D01*
G02X434650Y86418I-2161J1D01*
G01Y91930D01*
G37*
G36*
G01X448822D02*
G02X453146I2162J0D01*
G01Y86417D01*
G02X448822Y86418I-2162J1D01*
G01Y91930D01*
G37*
G36*
G01X462996D02*
G02X467318I2161J0D01*
G01Y86417D01*
G02X462996Y86418I-2161J1D01*
G01Y91930D01*
G37*
G36*
G01X455910Y116339D02*
G02X460232I2161J0D01*
G01Y110826D01*
G02X455910Y110827I-2161J1D01*
G01Y116339D01*
G37*
G36*
G01X434650Y77756D02*
G02X438972I2161J0D01*
G01Y72244D01*
G02X434650Y72245I-2161J1D01*
G01Y77756D01*
G37*
G36*
G01X427562Y87993D02*
G02X431886I2162J0D01*
G01Y82480D01*
G02X427562Y82481I-2162J1D01*
G01Y87993D01*
G37*
G36*
G01X441736D02*
G02X446060I2162J0D01*
G01Y82480D01*
G02X441736Y82481I-2162J1D01*
G01Y87993D01*
G37*
G36*
G01X455910D02*
G02X460232I2161J0D01*
G01Y82480D01*
G02X455910Y82481I-2161J1D01*
G01Y87993D01*
G37*
G36*
G01X470082D02*
G02X474406I2162J0D01*
G01Y82480D01*
G02X470082Y82481I-2162J1D01*
G01Y87993D01*
G37*
G36*
G01X448822Y77756D02*
G02X453146I2162J0D01*
G01Y72244D01*
G02X448822Y72245I-2162J1D01*
G01Y77756D01*
G37*
G36*
G01X462996D02*
G02X467318I2161J0D01*
G01Y72244D01*
G02X462996Y72245I-2161J1D01*
G01Y77756D01*
G37*
G36*
G01X1530712Y91930D02*
G02X1535036I2162J0D01*
G01Y86417D01*
G02X1530712Y86418I-2162J1D01*
G01Y91930D01*
G37*
G36*
G01X1516540D02*
G02X1520862I2161J0D01*
G01Y86417D01*
G02X1516540Y86418I-2161J1D01*
G01Y91930D01*
G37*
G36*
G01X1502366D02*
G02X1506690I2162J0D01*
G01Y86417D01*
G02X1502366Y86418I-2162J1D01*
G01Y91930D01*
G37*
G36*
G01X1502356Y120276D02*
G02X1506700I2172J0D01*
G01Y114763D01*
G02X1502356Y114764I-2172J1D01*
G01Y120276D01*
G37*
G36*
G01X1530712D02*
G02X1535036I2162J0D01*
G01Y114763D01*
G02X1530712Y114764I-2162J1D01*
G01Y120276D01*
G37*
G36*
G01Y77756D02*
G02X1535036I2162J0D01*
G01Y72244D01*
G02X1530712Y72245I-2162J1D01*
G01Y77756D01*
G37*
G36*
G01X1516540D02*
G02X1520862I2161J0D01*
G01Y72244D01*
G02X1516540Y72245I-2161J1D01*
G01Y77756D01*
G37*
G36*
G01X1502366D02*
G02X1506690I2162J0D01*
G01Y72244D01*
G02X1502366Y72245I-2162J1D01*
G01Y77756D01*
G37*
G36*
G01X1523626Y87993D02*
G02X1527948I2161J0D01*
G01Y82480D01*
G02X1523626Y82481I-2161J1D01*
G01Y87993D01*
G37*
G36*
G01X1509452D02*
G02X1513776I2162J0D01*
G01Y82480D01*
G02X1509452Y82481I-2162J1D01*
G01Y87993D01*
G37*
G36*
G01X1495280D02*
G02X1499602I2161J0D01*
G01Y82480D01*
G02X1495280Y82481I-2161J1D01*
G01Y87993D01*
G37*
G36*
G01X1488192Y91930D02*
G02X1492516I2162J0D01*
G01Y86417D01*
G02X1488192Y86418I-2162J1D01*
G01Y91930D01*
G37*
G36*
G01X1445674D02*
G02X1449996I2161J0D01*
G01Y86417D01*
G02X1445674Y86418I-2161J1D01*
G01Y91930D01*
G37*
G36*
G01X1450006Y114764D02*
G02X1445664I-2171J0D01*
G01Y120277D01*
G02X1450006Y120276I2171J-1D01*
G01Y114764D01*
G37*
G36*
G01X1488192Y77756D02*
G02X1492516I2162J0D01*
G01Y72244D01*
G02X1488192Y72245I-2162J1D01*
G01Y77756D01*
G37*
G36*
G01X1445674D02*
G02X1449996I2161J0D01*
G01Y72244D01*
G02X1445674Y72245I-2161J1D01*
G01Y77756D01*
G37*
G36*
G01X1481106Y87993D02*
G02X1485430I2162J0D01*
G01Y82480D01*
G02X1481106Y82481I-2162J1D01*
G01Y87993D01*
G37*
G36*
G01X1431500Y91930D02*
G02X1435822I2161J0D01*
G01Y86417D01*
G02X1431500Y86418I-2161J1D01*
G01Y91930D01*
G37*
G36*
G01X1417326D02*
G02X1421650I2162J0D01*
G01Y86417D01*
G02X1417326Y86418I-2162J1D01*
G01Y91930D01*
G37*
G36*
G01X1403154D02*
G02X1407476I2161J0D01*
G01Y86417D01*
G02X1403154Y86418I-2161J1D01*
G01Y91930D01*
G37*
G36*
G01X1424414Y116339D02*
G02X1428736I2161J0D01*
G01Y110826D01*
G02X1424414Y110827I-2161J1D01*
G01Y116339D01*
G37*
G36*
G01X1431500Y77756D02*
G02X1435822I2161J0D01*
G01Y72244D01*
G02X1431500Y72245I-2161J1D01*
G01Y77756D01*
G37*
G36*
G01X1417326D02*
G02X1421650I2162J0D01*
G01Y72244D01*
G02X1417326Y72245I-2162J1D01*
G01Y77756D01*
G37*
G36*
G01X1403154D02*
G02X1407476I2161J0D01*
G01Y72244D01*
G02X1403154Y72245I-2161J1D01*
G01Y77756D01*
G37*
G36*
G01X1438586Y87993D02*
G02X1442910I2162J0D01*
G01Y82480D01*
G02X1438586Y82481I-2162J1D01*
G01Y87993D01*
G37*
G36*
G01X1424414D02*
G02X1428736I2161J0D01*
G01Y82480D01*
G02X1424414Y82481I-2161J1D01*
G01Y87993D01*
G37*
G36*
G01X1410240D02*
G02X1414564I2162J0D01*
G01Y82480D01*
G02X1410240Y82481I-2162J1D01*
G01Y87993D01*
G37*
G36*
G01X1396066D02*
G02X1400390I2162J0D01*
G01Y82480D01*
G02X1396066Y82481I-2162J1D01*
G01Y87993D01*
G37*
G54D51*
X111024Y153681D03*
Y606437D03*
Y1059193D03*
X235236Y153681D03*
Y606437D03*
Y1059193D03*
X359449Y153681D03*
Y606437D03*
Y1059193D03*
X483661Y153681D03*
Y606437D03*
Y1059193D03*
X607874Y153681D03*
Y606437D03*
Y1059193D03*
X732087Y153681D03*
Y1059193D03*
X949902Y-115157D03*
X1281693Y153681D03*
Y606437D03*
Y1059193D03*
X1405906Y153681D03*
Y606437D03*
Y1059193D03*
X1530118Y153681D03*
Y606437D03*
Y1059193D03*
X1654331Y153681D03*
Y606437D03*
Y1059193D03*
X1778543Y153681D03*
Y606437D03*
Y1059193D03*
X1902756Y153681D03*
Y606437D03*
Y1059193D03*
G54D52*
X111024Y302303D03*
Y755059D03*
Y1207815D03*
X235236Y302303D03*
Y755059D03*
Y1207815D03*
X359449Y302303D03*
Y755059D03*
Y1207815D03*
X483661Y302303D03*
Y755059D03*
Y1207815D03*
X607874Y302303D03*
Y755059D03*
Y1207815D03*
X732087Y302303D03*
Y755059D03*
Y1207815D03*
X1098524Y-115157D03*
X1281693Y302303D03*
Y755059D03*
Y1207815D03*
X1405906Y302303D03*
Y755059D03*
Y1207815D03*
X1530118Y302303D03*
Y755059D03*
Y1207815D03*
X1654331Y302303D03*
Y755059D03*
Y1207815D03*
X1778543Y302303D03*
Y755059D03*
Y1207815D03*
X1902756Y302303D03*
Y755059D03*
Y1207815D03*
G54D53*
X79000Y1301900D03*
X1826700Y77600D03*
X1908500Y1346800D03*
G54D50*
X80019Y51968D03*
X127263Y20472D03*
X631200Y51968D03*
X678444Y20472D03*
X1250689Y51969D03*
X1297933Y20472D03*
X1801870Y51969D03*
X1849114Y20472D03*
G54D54*
X173228Y1114173D03*
X670079D03*
X1343700D03*
X1840551D03*
G54D56*
X496653Y80906D03*
X1465157D03*
G54D49*
X103642Y36220D03*
X173228Y1062992D03*
X421653Y1141732D03*
X654822Y36220D03*
X670079Y1062992D03*
X1274311Y36220D03*
X1343701Y1062992D03*
X1592126Y1141732D03*
X1825492Y36220D03*
X1840551Y1062992D03*
G54D62*
X1465158Y110551D03*
G54D55*
X1903346Y803937D03*
G54D48*
X31496Y882677D03*
X168307Y646457D03*
X660236D03*
X718110Y820866D03*
X1366142Y646457D03*
X1462992Y866929D03*
X1602756Y646457D03*
X1894685Y21654D03*
G54D46*
X1797933Y1282666D03*
Y829910D03*
Y377154D03*
X1549901Y1282666D03*
Y829910D03*
Y377154D03*
X796457Y735444D03*
Y263003D03*
X627263Y1282666D03*
Y829910D03*
Y377154D03*
X131201Y1282666D03*
Y377154D03*
G54D61*
X1130459Y1351595D03*
X1126522Y1330335D03*
Y1259469D03*
X1130459Y1280729D03*
X1126522Y1188603D03*
X1102113Y1394115D03*
X1098176Y1401201D03*
X1102113Y1351595D03*
X1098176Y1372855D03*
Y1330335D03*
Y1301989D03*
X1102113Y1309075D03*
Y1323249D03*
Y1280729D03*
X1098176Y1259469D03*
X1102113Y1209863D03*
X1098176Y1216949D03*
Y1231123D03*
X1102113Y1238209D03*
Y1167343D03*
X1098176Y1160257D03*
Y1188603D03*
G54D47*
X1301870Y1282666D03*
Y829910D03*
Y377154D03*
X1181890Y1559854D03*
X1181870Y969280D03*
X961418Y1429932D03*
Y1087413D03*
X379232Y1282666D03*
Y829910D03*
Y377154D03*
X131200Y829910D03*
G54D60*
X1126522Y1344508D03*
Y1358682D03*
X1130459Y1365768D03*
Y1337422D03*
Y1252382D03*
Y1266556D03*
X1126522Y1273642D03*
Y1245296D03*
Y1174430D03*
X1130459Y1181516D03*
Y1195690D03*
X1102113Y1408288D03*
Y1365768D03*
X1098176Y1358682D03*
Y1344508D03*
X1102113Y1379942D03*
X1098176Y1387028D03*
X1102113Y1337422D03*
X1098176Y1316162D03*
Y1273642D03*
X1102113Y1266556D03*
Y1252382D03*
X1098176Y1287816D03*
X1102113Y1294902D03*
X1098176Y1245296D03*
Y1202776D03*
X1102113Y1224036D03*
Y1195690D03*
Y1181516D03*
X1098176Y1174430D03*
G54D59*
X1126522Y1401201D03*
X1130459Y1394115D03*
X1126522Y1372855D03*
X1130459Y1323249D03*
Y1309075D03*
X1126522Y1301989D03*
X1130459Y1238209D03*
X1126522Y1231123D03*
Y1216949D03*
X1130459Y1209863D03*
Y1167343D03*
X1126522Y1160257D03*
G54D58*
X1130459Y1408288D03*
X1126522Y1387028D03*
X1130459Y1379942D03*
X1126522Y1316162D03*
X1130459Y1294902D03*
X1126522Y1287816D03*
X1130459Y1224036D03*
X1126522Y1202776D03*
%LPC*%
G75*
G36*
G01X892537Y-2458D02*
X843050Y47029D01*
Y318311D01*
X820211Y341150D01*
X740711D01*
X722650Y359211D01*
Y460506D01*
G03Y464494I-1150J1994D01*
G01Y513502D01*
X716559Y519593D01*
X628209D01*
X626240Y521562D01*
Y612894D01*
X628480Y615134D01*
X684809D01*
X685714Y614229D01*
Y589912D01*
X689538Y586088D01*
X720401D01*
X722663Y588350D01*
Y613349D01*
X724448Y615134D01*
X825895D01*
X835650Y624889D01*
Y749589D01*
X864211Y778150D01*
X968189D01*
X981050Y765289D01*
Y579325D01*
G02X980522Y578946I-400J0D01*
G03X968304Y577689I-4735J-13985D01*
G02X967702Y578034I-202J345D01*
G01Y721764D01*
X963248Y726218D01*
X950707D01*
X948531Y724042D01*
G02X947856Y724406I-283J283D01*
G03X943310Y719860I-5730J1184D01*
G02X943674Y719185I81J-392D01*
G01X936910Y712420D01*
X935598D01*
X930219Y717800D01*
X924110D01*
X920166Y713855D01*
Y402074D01*
X925717Y396522D01*
X932378D01*
X936301Y400446D01*
X947925D01*
X952052Y396318D01*
X960143D01*
X967702Y403877D01*
Y551888D01*
G02X968304Y552233I400J0D01*
G03X980522Y550975I7484J12728D01*
G02X981050Y550596I128J-379D01*
G01Y3886D01*
X974706Y-2458D01*
X892537D01*
G37*
G36*
G01X963700Y405534D02*
X958486Y400320D01*
X953709D01*
X949582Y404447D01*
X934644D01*
X930721Y400524D01*
X927374D01*
X924167Y403731D01*
Y712198D01*
X925767Y713798D01*
X928562D01*
X933941Y708419D01*
X938567D01*
X952364Y722216D01*
X961591D01*
X963700Y720107D01*
Y573440D01*
G03Y556481I12087J-8480D01*
G01Y405534D01*
G37*
G36*
G01X1035550Y111490D02*
G03Y113596I-2047J1053D01*
G01Y760089D01*
X1054311Y778850D01*
X1156589D01*
X1170150Y765289D01*
Y720912D01*
G03X1170111Y718139I1818J-1412D01*
G01X1170150Y718086D01*
Y717314D01*
X1170111Y717261D01*
G03Y714539I1857J-1361D01*
G01X1170150Y714486D01*
Y713714D01*
X1170111Y713661D01*
G03X1170150Y710888I1857J-1361D01*
G01Y688889D01*
X1283689Y575350D01*
X1335506D01*
G03X1339494I1994J1150D01*
G01X1383196D01*
X1390182Y568364D01*
Y482743D01*
X1377689Y470250D01*
X1284989D01*
X1167650Y352911D01*
Y-7089D01*
X1150689Y-24050D01*
X1050111D01*
X1035550Y-9489D01*
Y96490D01*
G03Y98596I-2047J1053D01*
G01Y101490D01*
G03Y103596I-2047J1053D01*
G01Y106490D01*
G03Y108596I-2047J1053D01*
G01Y111490D01*
G37*
G36*
G01X1143011Y980235D02*
X1081053D01*
X1079193Y982095D01*
Y1037432D01*
X1090611Y1048850D01*
X1143970D01*
X1145832Y1046988D01*
Y983056D01*
X1143011Y980235D01*
G37*
%LPD*%
G75*
G36*
G01X924110Y338666D02*
X930219D01*
X935598Y333288D01*
X936910D01*
X943674Y340052D01*
G03X943310Y340727I-283J283D01*
G02X947856Y345273I-1184J5730D01*
G03X948531Y344909I392J-81D01*
G01X950707Y347084D01*
X963248D01*
X967702Y342631D01*
Y24744D01*
X960143Y17186D01*
X952052D01*
X947925Y21312D01*
X936301D01*
X932378Y17390D01*
X925717D01*
X920166Y22941D01*
Y334722D01*
X924110Y338666D01*
G37*
G36*
G01X956203Y534842D02*
X956208Y534833D01*
X948330Y530894D01*
X948327Y530899D01*
X948229Y530857D01*
G02X945676Y535977I-1183J2607D01*
G01X945762Y536027D01*
X945760Y536032D01*
X953637Y539971D01*
X953643Y539965D01*
X953704Y539992D01*
G02X956203Y534842I1217J-2591D01*
G37*
G36*
G01Y424606D02*
X956208Y424597D01*
X948330Y420658D01*
X948327Y420663D01*
X948229Y420621D01*
G02X945676Y425741I-1183J2607D01*
G01X945762Y425791D01*
X945760Y425796D01*
X953637Y429735D01*
X953643Y429729D01*
X953704Y429756D01*
G02X956203Y424606I1217J-2591D01*
G37*
G36*
G01X956156Y708159D02*
X948315Y704239D01*
X948314Y704238D01*
G02X945812Y709162I-1267J2454D01*
G01X953686Y713099D01*
G02X956156Y708159I1235J-2470D01*
G37*
G36*
G01Y692411D02*
X948315Y688491D01*
X948314Y688490D01*
G02X945812Y693414I-1267J2454D01*
G01X953686Y697351D01*
G02X956156Y692411I1235J-2470D01*
G37*
G36*
G01Y676663D02*
X948315Y672743D01*
X948314Y672742D01*
G02X945812Y677666I-1267J2454D01*
G01X953686Y681603D01*
G02X956156Y676663I1235J-2470D01*
G37*
G36*
G01X936089Y696183D02*
X935924Y696253D01*
X935922Y696249D01*
X928046Y700187D01*
Y700195D01*
X927943Y700252D01*
G02X930447Y705390I1388J2503D01*
G01X930612Y705320D01*
X930614Y705324D01*
X938491Y701386D01*
X938489Y701382D01*
X938657Y701283D01*
G02X936089Y696183I-1453J-2465D01*
G37*
G36*
G01Y680435D02*
X935924Y680505D01*
X935922Y680501D01*
X928046Y684439D01*
Y684447D01*
X927943Y684504D01*
G02X930447Y689642I1388J2503D01*
G01X930612Y689572D01*
X930614Y689576D01*
X938491Y685638D01*
X938489Y685634D01*
X938657Y685535D01*
G02X936089Y680435I-1453J-2465D01*
G37*
G36*
G01Y664687D02*
X935924Y664757D01*
X935922Y664753D01*
X928046Y668691D01*
Y668699D01*
X927943Y668756D01*
G02X930447Y673894I1388J2503D01*
G01X930612Y673824D01*
X930614Y673828D01*
X938491Y669890D01*
X938489Y669886D01*
X938657Y669787D01*
G02X936089Y664687I-1453J-2465D01*
G37*
G36*
G01X956156Y660915D02*
X948315Y656995D01*
X948314Y656994D01*
G02X945812Y661918I-1267J2454D01*
G01X953686Y665855D01*
G02X956156Y660915I1235J-2470D01*
G37*
G36*
G01X936089Y648939D02*
X935924Y649009D01*
X935922Y649005D01*
X928046Y652943D01*
Y652951D01*
X927943Y653008D01*
G02X930447Y658146I1388J2503D01*
G01X930612Y658076D01*
X930614Y658080D01*
X938491Y654142D01*
X938489Y654138D01*
X938657Y654039D01*
G02X936089Y648939I-1453J-2465D01*
G37*
G36*
G01X956210Y645060D02*
X948337Y641123D01*
G02X945758Y646277I-1290J2577D01*
G01X953632Y650214D01*
G02X956210Y645060I1289J-2577D01*
G37*
G36*
G01X935916Y633249D02*
X928085Y637165D01*
X928084D01*
G02X930620Y642340I1248J2597D01*
G01X938494Y638403D01*
G02X935916Y633249I-1289J-2577D01*
G37*
G36*
G01X945758Y630529D02*
X953631Y634466D01*
G02X956210Y629312I1290J-2577D01*
G01X948336Y625375D01*
G02X945758Y630529I-1289J2577D01*
G37*
G36*
G01X935916Y617501D02*
X928085Y621417D01*
X928084D01*
G02X930620Y626592I1248J2597D01*
G01X938494Y622655D01*
G02X935916Y617501I-1289J-2577D01*
G37*
G36*
G01Y601753D02*
X928085Y605669D01*
X928084D01*
G02X930620Y610844I1248J2597D01*
G01X938494Y606907D01*
G02X935916Y601753I-1289J-2577D01*
G37*
G36*
G01X945758Y614781D02*
X953631Y618718D01*
G02X956210Y613564I1290J-2577D01*
G01X948336Y609627D01*
G02X945758Y614781I-1289J2577D01*
G37*
G36*
G01X935916Y586005D02*
X928085Y589921D01*
X928084D01*
G02X930620Y595096I1248J2597D01*
G01X938494Y591159D01*
G02X935916Y586005I-1289J-2577D01*
G37*
G36*
G01X956210Y597816D02*
X948337Y593879D01*
G02X945758Y599033I-1290J2577D01*
G01X953632Y602970D01*
G02X956210Y597816I1289J-2577D01*
G37*
G36*
G01X936089Y538703D02*
X935924Y538773D01*
X935922Y538769D01*
X928046Y542707D01*
Y542715D01*
X927943Y542772D01*
G02X930447Y547910I1388J2503D01*
G01X930612Y547840D01*
X930614Y547844D01*
X938491Y543906D01*
X938489Y543902D01*
X938657Y543803D01*
G02X936089Y538703I-1453J-2465D01*
G37*
G36*
G01X956223Y503301D02*
X948392Y499386D01*
G02X945745Y504572I-1345J2582D01*
G01X953619Y508509D01*
G02X956223Y503301I1302J-2604D01*
G37*
G36*
G01X945745Y488824D02*
X953576Y492739D01*
G02X956223Y487553I1345J-2582D01*
G01X948349Y483616D01*
G02X945745Y488824I-1302J2604D01*
G37*
G36*
G01X935916Y507265D02*
X928085Y511181D01*
X928084D01*
G02X930620Y516356I1248J2597D01*
G01X938494Y512419D01*
G02X935916Y507265I-1289J-2577D01*
G37*
G36*
G01Y491517D02*
X928085Y495433D01*
X928084D01*
G02X930620Y500608I1248J2597D01*
G01X938494Y496671D01*
G02X935916Y491517I-1289J-2577D01*
G37*
G36*
G01X930620Y484860D02*
X938451Y480944D01*
X938452D01*
G02X935916Y475769I-1248J-2597D01*
G01X928042Y479706D01*
G02X930620Y484860I1289J2577D01*
G37*
G36*
G01X935916Y444273D02*
X928085Y448189D01*
X928084D01*
G02X930620Y453364I1248J2597D01*
G01X938494Y449427D01*
G02X935916Y444273I-1289J-2577D01*
G37*
G36*
G01X945758Y473049D02*
X953631Y476986D01*
G02X956210Y471832I1290J-2577D01*
G01X948336Y467895D01*
G02X945758Y473049I-1289J2577D01*
G37*
G36*
G01X956210Y456084D02*
X948337Y452147D01*
G02X945758Y457301I-1290J2577D01*
G01X953632Y461238D01*
G02X956210Y456084I1289J-2577D01*
G37*
G36*
G01X935916Y460021D02*
X928085Y463937D01*
X928084D01*
G02X930620Y469112I1248J2597D01*
G01X938494Y465175D01*
G02X935916Y460021I-1289J-2577D01*
G37*
G36*
G01X1115966Y724406D02*
G03X1116641Y724042I392J-81D01*
G01X1118817Y726218D01*
X1131358D01*
X1135812Y721764D01*
Y403877D01*
X1128253Y396318D01*
X1120162D01*
X1116035Y400446D01*
X1104411D01*
X1100488Y396522D01*
X1093827D01*
X1088276Y402074D01*
Y713855D01*
X1092220Y717800D01*
X1098329D01*
X1103708Y712420D01*
X1105020D01*
X1111784Y719185D01*
G03X1111420Y719860I-283J283D01*
G02X1115966Y724406I-1184J5730D01*
G37*
G36*
G01X1116641Y344909D02*
X1118817Y347084D01*
X1131358D01*
X1135812Y342631D01*
Y178849D01*
G02Y174151I-1702J-2349D01*
G01Y24744D01*
X1128253Y17186D01*
X1120162D01*
X1116035Y21312D01*
X1104411D01*
X1100488Y17390D01*
X1093827D01*
X1088276Y22941D01*
Y334722D01*
X1092220Y338666D01*
X1098329D01*
X1103708Y333288D01*
X1105020D01*
X1111784Y340052D01*
G03X1111420Y340727I-283J283D01*
G02X1115966Y345273I-1184J5730D01*
G03X1116641Y344909I392J-81D01*
G37*
G54D51*
X732087Y606437D03*
G54D57*
X942126Y437598D03*
G54D48*
X904921Y564961D03*
G54D47*
X1181890Y555917D03*
G54D60*
X1116286Y1038198D03*
G54D59*
X1126522Y1031111D03*
X1130459Y1024025D03*
X1126522Y1002765D03*
X1102113Y1024025D03*
X1098176Y1031111D03*
Y1002765D03*
G54D58*
X1130459Y1038198D03*
X1126522Y1016938D03*
X1130459Y1009852D03*
Y995678D03*
X1126522Y988592D03*
X1102113Y1009852D03*
X1098176Y1016938D03*
X1102113Y1038198D03*
X1098176Y988592D03*
X1102113Y995678D03*
%LPC*%
G75*
G36*
G01X958486Y21187D02*
X953709D01*
X949582Y25314D01*
X934644D01*
X930721Y21391D01*
X927374D01*
X924167Y24598D01*
Y333065D01*
X925767Y334665D01*
X928562D01*
X933941Y329286D01*
X938567D01*
X952364Y343083D01*
X961591D01*
X963700Y340974D01*
Y26401D01*
X958486Y21187D01*
G37*
G36*
G01X1121819D02*
X1117692Y25314D01*
X1102754D01*
X1098831Y21391D01*
X1095484D01*
X1092277Y24598D01*
Y333065D01*
X1093877Y334665D01*
X1096672D01*
X1102051Y329286D01*
X1106677D01*
X1120474Y343083D01*
X1129701D01*
X1131810Y340974D01*
Y176592D01*
G03Y176408I2300J-92D01*
G01Y26401D01*
X1126596Y21187D01*
X1121819D01*
G37*
G36*
G01X1131810Y720107D02*
Y405534D01*
X1126596Y400320D01*
X1121819D01*
X1117692Y404447D01*
X1102754D01*
X1098831Y400524D01*
X1095484D01*
X1092277Y403731D01*
Y712198D01*
X1093877Y713798D01*
X1096672D01*
X1102051Y708419D01*
X1106677D01*
X1120474Y722216D01*
X1129701D01*
X1131810Y720107D01*
G37*
%LPD*%
G75*
G36*
G01X948282Y277845D02*
G02X945812Y282785I-1235J2470D01*
G01X953653Y286705D01*
X953654Y286706D01*
G02X956156Y281782I1267J-2454D01*
G01X948282Y277845D01*
G37*
G36*
G01Y293593D02*
G02X945812Y298533I-1235J2470D01*
G01X953653Y302453D01*
X953654Y302454D01*
G02X956156Y297530I1267J-2454D01*
G01X948282Y293593D01*
G37*
G36*
G01Y309341D02*
G02X945812Y314281I-1235J2470D01*
G01X953653Y318201D01*
X953654Y318202D01*
G02X956156Y313278I1267J-2454D01*
G01X948282Y309341D01*
G37*
G36*
G01X953686Y333966D02*
G02X956156Y329026I1235J-2470D01*
G01X948315Y325106D01*
X948314Y325105D01*
G02X945812Y330029I-1267J2454D01*
G01X953686Y333966D01*
G37*
G36*
G01X936089Y317050D02*
X935924Y317120D01*
X935922Y317116D01*
X928046Y321054D01*
Y321062D01*
X927943Y321119D01*
G02X930447Y326257I1388J2503D01*
G01X930612Y326187D01*
X930614Y326191D01*
X938491Y322253D01*
X938489Y322249D01*
X938657Y322150D01*
G02X936089Y317050I-1453J-2465D01*
G37*
G36*
G01Y301302D02*
X935924Y301372D01*
X935922Y301368D01*
X928046Y305306D01*
Y305314D01*
X927943Y305371D01*
G02X930447Y310509I1388J2503D01*
G01X930612Y310439D01*
X930614Y310443D01*
X938491Y306505D01*
X938489Y306501D01*
X938657Y306402D01*
G02X936089Y301302I-1453J-2465D01*
G37*
G36*
G01Y285554D02*
X935924Y285624D01*
X935922Y285620D01*
X928046Y289558D01*
Y289566D01*
X927943Y289623D01*
G02X930447Y294761I1388J2503D01*
G01X930612Y294691D01*
X930614Y294695D01*
X938491Y290757D01*
X938489Y290753D01*
X938657Y290654D01*
G02X936089Y285554I-1453J-2465D01*
G37*
G36*
G01X953686Y239478D02*
G02X956156Y234538I1235J-2470D01*
G01X948315Y230618D01*
X948314Y230617D01*
G02X945812Y235541I-1267J2454D01*
G01X953686Y239478D01*
G37*
G36*
G01X936089Y269806D02*
X935924Y269876D01*
X935922Y269872D01*
X928046Y273810D01*
Y273818D01*
X927943Y273875D01*
G02X930447Y279013I1388J2503D01*
G01X930612Y278943D01*
X930614Y278947D01*
X938491Y275009D01*
X938489Y275005D01*
X938657Y274906D01*
G02X936089Y269806I-1453J-2465D01*
G37*
G36*
G01X953686Y270974D02*
G02X956156Y266034I1235J-2470D01*
G01X948315Y262114D01*
X948314Y262113D01*
G02X945812Y267037I-1267J2454D01*
G01X953686Y270974D01*
G37*
G36*
G01X936089Y254058D02*
X935924Y254128D01*
X935922Y254124D01*
X928045Y258062D01*
X928047Y258066D01*
X927879Y258165D01*
G02X930447Y263265I1453J2465D01*
G01X930612Y263195D01*
X930614Y263199D01*
X938490Y259261D01*
Y259253D01*
X938593Y259196D01*
G02X936089Y254058I-1388J-2503D01*
G37*
G36*
G01Y238310D02*
X935924Y238380D01*
X935922Y238376D01*
X928046Y242314D01*
Y242322D01*
X927943Y242379D01*
G02X930447Y247517I1388J2503D01*
G01X930612Y247447D01*
X930614Y247451D01*
X938491Y243513D01*
X938489Y243509D01*
X938657Y243410D01*
G02X936089Y238310I-1453J-2465D01*
G37*
G36*
G01X953686Y255226D02*
G02X956156Y250286I1235J-2470D01*
G01X948315Y246366D01*
X948314Y246365D01*
G02X945812Y251289I-1267J2454D01*
G01X953686Y255226D01*
G37*
G36*
G01Y192234D02*
G02X956156Y187294I1235J-2470D01*
G01X948315Y183374D01*
X948314Y183373D01*
G02X945812Y188297I-1267J2454D01*
G01X953686Y192234D01*
G37*
G36*
G01X948282Y199105D02*
G02X945812Y204045I-1235J2470D01*
G01X953653Y207965D01*
X953654Y207966D01*
G02X956156Y203042I1267J-2454D01*
G01X948282Y199105D01*
G37*
G36*
G01X953686Y223730D02*
G02X956156Y218790I1235J-2470D01*
G01X948315Y214870D01*
X948314Y214869D01*
G02X945812Y219793I-1267J2454D01*
G01X953686Y223730D01*
G37*
G36*
G01X936089Y191066D02*
X935924Y191136D01*
X935922Y191132D01*
X928046Y195070D01*
Y195078D01*
X927943Y195135D01*
G02X930447Y200273I1388J2503D01*
G01X930612Y200203D01*
X930614Y200207D01*
X938491Y196269D01*
X938489Y196265D01*
X938657Y196166D01*
G02X936089Y191066I-1453J-2465D01*
G37*
G36*
G01Y222562D02*
X935924Y222632D01*
X935922Y222628D01*
X928046Y226566D01*
Y226574D01*
X927943Y226631D01*
G02X930447Y231769I1388J2503D01*
G01X930612Y231699D01*
X930614Y231703D01*
X938491Y227765D01*
X938489Y227761D01*
X938657Y227662D01*
G02X936089Y222562I-1453J-2465D01*
G37*
G36*
G01Y206814D02*
X935924Y206884D01*
X935922Y206880D01*
X928046Y210818D01*
Y210826D01*
X927943Y210883D01*
G02X930447Y216021I1388J2503D01*
G01X930612Y215951D01*
X930614Y215955D01*
X938491Y212017D01*
X938489Y212013D01*
X938657Y211914D01*
G02X936089Y206814I-1453J-2465D01*
G37*
G36*
G01X948332Y136015D02*
G02X945762Y141151I-1285J2568D01*
G01X953636Y145088D01*
G02X956206Y139952I1285J-2568D01*
G01X948332Y136015D01*
G37*
G36*
G01X936089Y159570D02*
X935924Y159640D01*
X935922Y159636D01*
X928046Y163574D01*
Y163582D01*
X927943Y163639D01*
G02X930447Y168777I1388J2503D01*
G01X930612Y168707D01*
X930614Y168711D01*
X938491Y164773D01*
X938489Y164769D01*
X938657Y164670D01*
G02X936089Y159570I-1453J-2465D01*
G37*
G36*
G01X953686Y160738D02*
G02X956156Y155798I1235J-2470D01*
G01X948315Y151878D01*
X948314Y151877D01*
G02X945812Y156801I-1267J2454D01*
G01X953686Y160738D01*
G37*
G36*
G01Y176486D02*
G02X956156Y171546I1235J-2470D01*
G01X948315Y167626D01*
X948314Y167625D01*
G02X945812Y172549I-1267J2454D01*
G01X953686Y176486D01*
G37*
G36*
G01X936089Y143822D02*
X935924Y143892D01*
X935922Y143888D01*
X928046Y147826D01*
Y147834D01*
X927943Y147891D01*
G02X930447Y153029I1388J2503D01*
G01X930612Y152959D01*
X930614Y152963D01*
X938491Y149025D01*
X938489Y149021D01*
X938657Y148922D01*
G02X936089Y143822I-1453J-2465D01*
G37*
G36*
G01Y175318D02*
X935924Y175388D01*
X935922Y175384D01*
X928046Y179322D01*
Y179330D01*
X927943Y179387D01*
G02X930447Y184525I1388J2503D01*
G01X930612Y184455D01*
X930614Y184459D01*
X938491Y180521D01*
X938489Y180517D01*
X938657Y180418D01*
G02X936089Y175318I-1453J-2465D01*
G37*
G36*
G01X928084Y45434D02*
G02X930620Y50609I1248J2597D01*
G01X938494Y46672D01*
G02X935916Y41518I-1289J-2577D01*
G01X928085Y45434D01*
X928084D01*
G37*
G36*
G01X936089Y65082D02*
X935924Y65152D01*
X935922Y65148D01*
X928046Y69086D01*
Y69094D01*
X927943Y69151D01*
G02X930447Y74289I1388J2503D01*
G01X930612Y74219D01*
X930614Y74223D01*
X938491Y70285D01*
X938489Y70281D01*
X938657Y70182D01*
G02X936089Y65082I-1453J-2465D01*
G37*
G36*
G01X1116392Y277845D02*
G02X1113922Y282785I-1235J2470D01*
G01X1121763Y286705D01*
X1121764Y286706D01*
G02X1124266Y281782I1267J-2454D01*
G01X1116392Y277845D01*
G37*
G36*
G01Y293593D02*
G02X1113922Y298533I-1235J2470D01*
G01X1121763Y302453D01*
X1121764Y302454D01*
G02X1124266Y297530I1267J-2454D01*
G01X1116392Y293593D01*
G37*
G36*
G01Y325089D02*
G02X1113922Y330029I-1235J2470D01*
G01X1121763Y333949D01*
X1121764Y333950D01*
G02X1124266Y329026I1267J-2454D01*
G01X1116392Y325089D01*
G37*
G36*
G01Y309341D02*
G02X1113922Y314281I-1235J2470D01*
G01X1121763Y318201D01*
X1121764Y318202D01*
G02X1124266Y313278I1267J-2454D01*
G01X1116392Y309341D01*
G37*
G36*
G01Y230601D02*
G02X1113922Y235541I-1235J2470D01*
G01X1121763Y239461D01*
X1121764Y239462D01*
G02X1124266Y234538I1267J-2454D01*
G01X1116392Y230601D01*
G37*
G36*
G01Y262097D02*
G02X1113922Y267037I-1235J2470D01*
G01X1121763Y270957D01*
X1121764Y270958D01*
G02X1124266Y266034I1267J-2454D01*
G01X1116392Y262097D01*
G37*
G36*
G01Y246349D02*
G02X1113922Y251289I-1235J2470D01*
G01X1121763Y255209D01*
X1121764Y255210D01*
G02X1124266Y250286I1267J-2454D01*
G01X1116392Y246349D01*
G37*
G36*
G01Y183357D02*
G02X1113922Y188297I-1235J2470D01*
G01X1121763Y192217D01*
X1121764Y192218D01*
G02X1124266Y187294I1267J-2454D01*
G01X1116392Y183357D01*
G37*
G36*
G01Y214853D02*
G02X1113922Y219793I-1235J2470D01*
G01X1121763Y223713D01*
X1121764Y223714D01*
G02X1124266Y218790I1267J-2454D01*
G01X1116392Y214853D01*
G37*
G36*
G01Y199105D02*
G02X1113922Y204045I-1235J2470D01*
G01X1121763Y207965D01*
X1121764Y207966D01*
G02X1124266Y203042I1267J-2454D01*
G01X1116392Y199105D01*
G37*
G36*
G01X1121741Y145097D02*
G02X1124320Y139943I1290J-2577D01*
G01X1116446Y136006D01*
G02X1113868Y141160I-1289J2577D01*
G01X1121741Y145097D01*
G37*
G36*
G01X1116392Y167609D02*
G02X1113922Y172549I-1235J2470D01*
G01X1121763Y176469D01*
X1121764Y176470D01*
G02X1124266Y171546I1267J-2454D01*
G01X1116392Y167609D01*
G37*
G36*
G01Y151861D02*
G02X1113922Y156801I-1235J2470D01*
G01X1121763Y160721D01*
X1121764Y160722D01*
G02X1124266Y155798I1267J-2454D01*
G01X1116392Y151861D01*
G37*
G36*
G01X1104199Y301302D02*
X1104034Y301372D01*
X1104032Y301368D01*
X1096156Y305306D01*
Y305314D01*
X1096053Y305371D01*
G02X1098557Y310509I1388J2503D01*
G01X1098722Y310439D01*
X1098724Y310443D01*
X1106601Y306505D01*
X1106599Y306501D01*
X1106767Y306402D01*
G02X1104199Y301302I-1453J-2465D01*
G37*
G36*
G01Y285554D02*
X1104034Y285624D01*
X1104032Y285620D01*
X1096156Y289558D01*
Y289566D01*
X1096053Y289623D01*
G02X1098557Y294761I1388J2503D01*
G01X1098722Y294691D01*
X1098724Y294695D01*
X1106601Y290757D01*
X1106599Y290753D01*
X1106767Y290654D01*
G02X1104199Y285554I-1453J-2465D01*
G37*
G36*
G01Y317050D02*
X1104034Y317120D01*
X1104032Y317116D01*
X1096156Y321054D01*
Y321062D01*
X1096053Y321119D01*
G02X1098557Y326257I1388J2503D01*
G01X1098722Y326187D01*
X1098724Y326191D01*
X1106601Y322253D01*
X1106599Y322249D01*
X1106767Y322150D01*
G02X1104199Y317050I-1453J-2465D01*
G37*
G36*
G01Y254058D02*
X1104034Y254128D01*
X1104032Y254124D01*
X1096156Y258062D01*
Y258070D01*
X1096053Y258127D01*
G02X1098557Y263265I1388J2503D01*
G01X1098722Y263195D01*
X1098724Y263199D01*
X1106601Y259261D01*
X1106599Y259257D01*
X1106767Y259158D01*
G02X1104199Y254058I-1453J-2465D01*
G37*
G36*
G01Y238310D02*
X1104034Y238380D01*
X1104032Y238376D01*
X1096156Y242314D01*
Y242322D01*
X1096053Y242379D01*
G02X1098557Y247517I1388J2503D01*
G01X1098722Y247447D01*
X1098724Y247451D01*
X1106601Y243513D01*
X1106599Y243509D01*
X1106767Y243410D01*
G02X1104199Y238310I-1453J-2465D01*
G37*
G36*
G01Y269806D02*
X1104034Y269876D01*
X1104032Y269872D01*
X1096156Y273810D01*
Y273818D01*
X1096053Y273875D01*
G02X1098557Y279013I1388J2503D01*
G01X1098722Y278943D01*
X1098724Y278947D01*
X1106601Y275009D01*
X1106599Y275005D01*
X1106767Y274906D01*
G02X1104199Y269806I-1453J-2465D01*
G37*
G36*
G01Y222562D02*
X1104034Y222632D01*
X1104032Y222628D01*
X1096156Y226566D01*
Y226574D01*
X1096053Y226631D01*
G02X1098557Y231769I1388J2503D01*
G01X1098722Y231699D01*
X1098724Y231703D01*
X1106601Y227765D01*
X1106599Y227761D01*
X1106767Y227662D01*
G02X1104199Y222562I-1453J-2465D01*
G37*
G36*
G01Y206814D02*
X1104034Y206884D01*
X1104032Y206880D01*
X1096156Y210818D01*
Y210826D01*
X1096053Y210883D01*
G02X1098557Y216021I1388J2503D01*
G01X1098722Y215951D01*
X1098724Y215955D01*
X1106601Y212017D01*
X1106599Y212013D01*
X1106767Y211914D01*
G02X1104199Y206814I-1453J-2465D01*
G37*
G36*
G01Y191066D02*
X1104034Y191136D01*
X1104032Y191132D01*
X1096156Y195070D01*
Y195078D01*
X1096053Y195135D01*
G02X1098557Y200273I1388J2503D01*
G01X1098722Y200203D01*
X1098724Y200207D01*
X1106601Y196269D01*
X1106599Y196265D01*
X1106767Y196166D01*
G02X1104199Y191066I-1453J-2465D01*
G37*
G36*
G01Y175318D02*
X1104034Y175388D01*
X1104032Y175384D01*
X1096156Y179322D01*
Y179330D01*
X1096053Y179387D01*
G02X1098557Y184525I1388J2503D01*
G01X1098722Y184455D01*
X1098724Y184459D01*
X1106601Y180521D01*
X1106599Y180517D01*
X1106767Y180418D01*
G02X1104199Y175318I-1453J-2465D01*
G37*
G36*
G01Y143822D02*
X1104034Y143892D01*
X1104032Y143888D01*
X1096156Y147826D01*
Y147834D01*
X1096053Y147891D01*
G02X1098557Y153029I1388J2503D01*
G01X1098722Y152959D01*
X1098724Y152963D01*
X1106601Y149025D01*
X1106599Y149021D01*
X1106767Y148922D01*
G02X1104199Y143822I-1453J-2465D01*
G37*
G36*
G01Y159570D02*
X1104034Y159640D01*
X1104032Y159636D01*
X1096156Y163574D01*
Y163582D01*
X1096053Y163639D01*
G02X1098557Y168777I1388J2503D01*
G01X1098722Y168707D01*
X1098724Y168711D01*
X1106601Y164773D01*
X1106599Y164769D01*
X1106767Y164670D01*
G02X1104199Y159570I-1453J-2465D01*
G37*
G36*
G01X1096194Y45434D02*
G02X1098730Y50609I1248J2597D01*
G01X1106604Y46672D01*
G02X1104026Y41518I-1289J-2577D01*
G01X1096195Y45434D01*
X1096194D01*
G37*
G36*
G01X1104199Y65082D02*
X1104034Y65152D01*
X1104032Y65148D01*
X1096156Y69086D01*
Y69094D01*
X1096053Y69151D01*
G02X1098557Y74289I1388J2503D01*
G01X1098722Y74219D01*
X1098724Y74223D01*
X1106601Y70285D01*
X1106599Y70281D01*
X1106767Y70182D01*
G02X1104199Y65082I-1453J-2465D01*
G37*
G36*
G01X1124313Y534842D02*
X1124318Y534833D01*
X1116440Y530894D01*
X1116437Y530899D01*
X1116339Y530857D01*
G02X1113786Y535977I-1183J2607D01*
G01X1113872Y536027D01*
X1113870Y536032D01*
X1121747Y539971D01*
X1121753Y539965D01*
X1121814Y539992D01*
G02X1124313Y534842I1217J-2591D01*
G37*
G36*
G01X1113922Y693414D02*
X1121763Y697334D01*
X1121764Y697335D01*
G02X1124266Y692411I1267J-2454D01*
G01X1116392Y688474D01*
G02X1113922Y693414I-1235J2470D01*
G37*
G36*
G01Y677666D02*
X1121763Y681586D01*
X1121764Y681587D01*
G02X1124266Y676663I1267J-2454D01*
G01X1116392Y672726D01*
G02X1113922Y677666I-1235J2470D01*
G37*
G36*
G01Y709162D02*
X1121763Y713082D01*
X1121764Y713083D01*
G02X1124266Y708159I1267J-2454D01*
G01X1116392Y704222D01*
G02X1113922Y709162I-1235J2470D01*
G37*
G36*
G01Y661918D02*
X1121763Y665838D01*
X1121764Y665839D01*
G02X1124266Y660915I1267J-2454D01*
G01X1116392Y656978D01*
G02X1113922Y661918I-1235J2470D01*
G37*
G36*
G01Y646170D02*
X1121763Y650090D01*
X1121764Y650091D01*
G02X1124266Y645167I1267J-2454D01*
G01X1116392Y641230D01*
G02X1113922Y646170I-1235J2470D01*
G37*
G36*
G01X1124266Y629419D02*
X1116425Y625499D01*
X1116424Y625498D01*
G02X1113922Y630422I-1267J2454D01*
G01X1121796Y634359D01*
G02X1124266Y629419I1235J-2470D01*
G37*
G36*
G01X1113922Y614674D02*
X1121763Y618594D01*
X1121764Y618595D01*
G02X1124266Y613671I1267J-2454D01*
G01X1116392Y609734D01*
G02X1113922Y614674I-1235J2470D01*
G37*
G36*
G01Y598926D02*
X1121763Y602846D01*
X1121764Y602847D01*
G02X1124266Y597923I1267J-2454D01*
G01X1116392Y593986D01*
G02X1113922Y598926I-1235J2470D01*
G37*
G36*
G01Y504438D02*
X1121763Y508358D01*
X1121764Y508359D01*
G02X1124266Y503435I1267J-2454D01*
G01X1116392Y499498D01*
G02X1113922Y504438I-1235J2470D01*
G37*
G36*
G01Y488690D02*
X1121763Y492610D01*
X1121764Y492611D01*
G02X1124266Y487687I1267J-2454D01*
G01X1116392Y483750D01*
G02X1113922Y488690I-1235J2470D01*
G37*
G36*
G01Y472942D02*
X1121763Y476862D01*
X1121764Y476863D01*
G02X1124266Y471939I1267J-2454D01*
G01X1116392Y468002D01*
G02X1113922Y472942I-1235J2470D01*
G37*
G36*
G01Y457194D02*
X1121763Y461114D01*
X1121764Y461115D01*
G02X1124266Y456191I1267J-2454D01*
G01X1116392Y452254D01*
G02X1113922Y457194I-1235J2470D01*
G37*
G36*
G01X1113872Y425796D02*
X1121746Y429733D01*
G02X1124316Y424597I1285J-2568D01*
G01X1116442Y420660D01*
G02X1113872Y425796I-1285J2568D01*
G37*
G36*
G01X1104199Y696183D02*
X1104034Y696253D01*
X1104032Y696249D01*
X1096156Y700187D01*
Y700195D01*
X1096053Y700252D01*
G02X1098557Y705390I1388J2503D01*
G01X1098722Y705320D01*
X1098724Y705324D01*
X1106601Y701386D01*
X1106599Y701382D01*
X1106767Y701283D01*
G02X1104199Y696183I-1453J-2465D01*
G37*
G36*
G01Y680435D02*
X1104034Y680505D01*
X1104032Y680501D01*
X1096156Y684439D01*
Y684447D01*
X1096053Y684504D01*
G02X1098557Y689642I1388J2503D01*
G01X1098722Y689572D01*
X1098724Y689576D01*
X1106601Y685638D01*
X1106599Y685634D01*
X1106767Y685535D01*
G02X1104199Y680435I-1453J-2465D01*
G37*
G36*
G01Y664687D02*
X1104034Y664757D01*
X1104032Y664753D01*
X1096156Y668691D01*
Y668699D01*
X1096053Y668756D01*
G02X1098557Y673894I1388J2503D01*
G01X1098722Y673824D01*
X1098724Y673828D01*
X1106601Y669890D01*
X1106599Y669886D01*
X1106767Y669787D01*
G02X1104199Y664687I-1453J-2465D01*
G37*
G36*
G01Y648939D02*
X1104034Y649009D01*
X1104032Y649005D01*
X1096156Y652943D01*
Y652951D01*
X1096053Y653008D01*
G02X1098557Y658146I1388J2503D01*
G01X1098722Y658076D01*
X1098724Y658080D01*
X1106601Y654142D01*
X1106599Y654138D01*
X1106767Y654039D01*
G02X1104199Y648939I-1453J-2465D01*
G37*
G36*
G01X1104039Y617528D02*
X1096133Y621481D01*
X1096062Y621519D01*
G02X1098717Y626565I1379J2496D01*
G01X1106591Y622628D01*
G02X1104039Y617528I-1276J-2550D01*
G37*
G36*
G01Y633276D02*
X1096133Y637229D01*
X1096062Y637267D01*
G02X1098717Y642313I1379J2496D01*
G01X1106591Y638376D01*
G02X1104039Y633276I-1276J-2550D01*
G37*
G36*
G01Y586032D02*
X1096133Y589985D01*
X1096062Y590023D01*
G02X1098717Y595069I1379J2496D01*
G01X1106591Y591132D01*
G02X1104039Y586032I-1276J-2550D01*
G37*
G36*
G01Y601780D02*
X1096133Y605733D01*
X1096062Y605771D01*
G02X1098717Y610817I1379J2496D01*
G01X1106591Y606880D01*
G02X1104039Y601780I-1276J-2550D01*
G37*
G36*
G01X1104199Y538703D02*
X1104034Y538773D01*
X1104032Y538769D01*
X1096156Y542707D01*
Y542715D01*
X1096053Y542772D01*
G02X1098557Y547910I1388J2503D01*
G01X1098722Y547840D01*
X1098724Y547844D01*
X1106601Y543906D01*
X1106599Y543902D01*
X1106767Y543803D01*
G02X1104199Y538703I-1453J-2465D01*
G37*
G36*
G01X1104039Y475796D02*
X1096133Y479749D01*
X1096062Y479787D01*
G02X1098717Y484833I1379J2496D01*
G01X1106591Y480896D01*
G02X1104039Y475796I-1276J-2550D01*
G37*
G36*
G01Y491544D02*
X1096133Y495497D01*
X1096062Y495535D01*
G02X1098717Y500581I1379J2496D01*
G01X1106591Y496644D01*
G02X1104039Y491544I-1276J-2550D01*
G37*
G36*
G01Y507292D02*
X1096133Y511245D01*
X1096062Y511283D01*
G02X1098717Y516329I1379J2496D01*
G01X1106591Y512392D01*
G02X1104039Y507292I-1276J-2550D01*
G37*
G36*
G01X1098676Y453257D02*
X1106550Y449320D01*
G02X1104080Y444380I-1235J-2470D01*
G01X1096239Y448301D01*
X1096238D01*
G02X1098676Y453257I1203J2486D01*
G37*
G36*
G01X1104039Y460048D02*
X1096133Y464001D01*
X1096062Y464039D01*
G02X1098717Y469085I1379J2496D01*
G01X1106591Y465148D01*
G02X1104039Y460048I-1276J-2550D01*
G37*
G54D57*
X942126Y58465D03*
X1110236D03*
Y437598D03*
G54D23*
X127988Y190242D03*
Y185742D03*
Y194242D03*
Y181742D03*
Y634498D03*
Y638498D03*
Y642998D03*
Y646998D03*
Y1087254D03*
Y1091254D03*
Y1095754D03*
Y1099754D03*
X252200Y190242D03*
Y185742D03*
Y194242D03*
Y181742D03*
Y634498D03*
Y638498D03*
Y642998D03*
Y646998D03*
Y1087254D03*
Y1091254D03*
Y1095754D03*
Y1099754D03*
X376413Y190242D03*
Y185742D03*
Y194242D03*
Y181742D03*
Y634498D03*
Y638498D03*
Y642998D03*
Y646998D03*
Y1087254D03*
Y1091254D03*
Y1095754D03*
Y1099754D03*
X500625Y190242D03*
Y185742D03*
Y194242D03*
Y181742D03*
Y634498D03*
Y638498D03*
Y642998D03*
Y646998D03*
Y1087254D03*
Y1091254D03*
Y1095754D03*
Y1099754D03*
X624838Y190242D03*
Y185742D03*
Y194242D03*
Y181742D03*
Y634498D03*
Y638498D03*
Y642998D03*
Y646998D03*
Y1087254D03*
Y1091254D03*
Y1095754D03*
Y1099754D03*
X749051Y190242D03*
Y185742D03*
Y194242D03*
Y181742D03*
Y634498D03*
Y638498D03*
Y642998D03*
Y646998D03*
Y1087254D03*
Y1091254D03*
Y1095754D03*
Y1099754D03*
X1066750Y1224035D03*
X1070750D03*
X1075250D03*
X1079250D03*
X1066750Y1209862D03*
X1070750D03*
X1075250D03*
X1079250D03*
X1066750Y1216949D03*
X1070750D03*
X1075250D03*
X1079250D03*
X1066750Y1231122D03*
X1070750D03*
X1075250D03*
X1079250D03*
X1066750Y1238209D03*
X1070750D03*
X1075250D03*
X1079250D03*
X1066750Y1245295D03*
X1070750D03*
X1075250D03*
X1079250D03*
X1066750Y1301988D03*
X1070750D03*
X1075250D03*
X1079250D03*
X1066750Y1309075D03*
X1070750D03*
X1075250D03*
X1079250D03*
X1066750Y1316161D03*
X1070750D03*
X1075250D03*
X1079250D03*
X1066750Y1323248D03*
X1070750D03*
X1075250D03*
X1079250D03*
X1066750Y1294902D03*
X1070750D03*
X1075250D03*
X1079250D03*
X1066750Y1330335D03*
X1070750D03*
X1075250D03*
X1079250D03*
X1066750Y1387028D03*
X1070750D03*
X1075250D03*
X1079250D03*
X1066750Y1394114D03*
X1070750D03*
X1075250D03*
X1079250D03*
X1066750Y1401201D03*
X1070750D03*
X1075250D03*
X1079250D03*
X1066750Y1408287D03*
X1070750D03*
X1075250D03*
X1079250D03*
X1066750Y1415374D03*
X1070750D03*
X1075250D03*
X1079250D03*
X1066750Y1379941D03*
X1070750D03*
X1075250D03*
X1079250D03*
X1278900Y182823D03*
X1274900D03*
X1270400D03*
X1266400D03*
X1261250Y167823D03*
X1256750D03*
X1265250D03*
X1252750D03*
X1278500Y634498D03*
Y638498D03*
Y642998D03*
Y646998D03*
X1259800Y631998D03*
Y627998D03*
Y623498D03*
Y619498D03*
Y1080754D03*
Y1076254D03*
Y1072254D03*
X1278500Y1087254D03*
Y1091254D03*
Y1095754D03*
Y1099754D03*
X1259800Y1084754D03*
X1376963Y167823D03*
X1402713Y181742D03*
Y185742D03*
Y190242D03*
Y194242D03*
X1380963Y167823D03*
X1385463D03*
X1389463D03*
X1402713Y634498D03*
Y638498D03*
Y642998D03*
Y646998D03*
X1384013Y631998D03*
Y627998D03*
Y623498D03*
Y619498D03*
Y1080754D03*
Y1076254D03*
Y1072254D03*
X1402713Y1087254D03*
Y1091254D03*
Y1095754D03*
Y1099754D03*
X1384013Y1084754D03*
X1515450Y181700D03*
X1511450D03*
X1506950D03*
X1502950D03*
X1508225Y631998D03*
Y627998D03*
Y623498D03*
Y619498D03*
Y1080754D03*
Y1076254D03*
Y1072254D03*
Y1084754D03*
X1526925Y181742D03*
Y185742D03*
Y190242D03*
Y194242D03*
Y634498D03*
Y638498D03*
Y642998D03*
Y646998D03*
Y1087254D03*
Y1091254D03*
Y1095754D03*
Y1099754D03*
X1651138Y181742D03*
Y185742D03*
Y190242D03*
Y194242D03*
X1632438Y179242D03*
Y175242D03*
Y170742D03*
Y166742D03*
X1651138Y634498D03*
Y638498D03*
Y642998D03*
Y646998D03*
X1632438Y631998D03*
Y627998D03*
Y623498D03*
Y619498D03*
Y1080754D03*
Y1076254D03*
Y1072254D03*
X1651138Y1087254D03*
Y1091254D03*
Y1095754D03*
Y1099754D03*
X1632438Y1084754D03*
X1756650Y179242D03*
Y175242D03*
Y170742D03*
Y166742D03*
X1725350Y634498D03*
Y638498D03*
Y642998D03*
Y646998D03*
X1731650Y631998D03*
Y627998D03*
Y623498D03*
Y619498D03*
X1756650Y1080754D03*
Y1076254D03*
Y1072254D03*
Y1084754D03*
X1775350Y181742D03*
Y185742D03*
Y190242D03*
Y194242D03*
Y1087254D03*
Y1091254D03*
Y1095754D03*
Y1099754D03*
X1899563Y181742D03*
Y185742D03*
Y190242D03*
Y194242D03*
X1880863Y179242D03*
Y175242D03*
Y170742D03*
Y166742D03*
X1899563Y634498D03*
Y638498D03*
Y642998D03*
Y646998D03*
X1880863Y631998D03*
Y627998D03*
Y623498D03*
Y619498D03*
Y1080754D03*
Y1076254D03*
Y1072254D03*
X1899563Y1087254D03*
Y1091254D03*
Y1095754D03*
Y1099754D03*
X1880863Y1084754D03*
G54D12*
X20000Y60000D03*
Y80000D03*
Y100000D03*
Y120000D03*
Y140000D03*
Y160000D03*
Y180000D03*
Y200000D03*
Y220000D03*
Y240000D03*
Y260000D03*
Y280000D03*
Y300000D03*
Y320000D03*
Y340000D03*
Y360000D03*
Y380000D03*
Y400000D03*
Y420000D03*
Y440000D03*
X15000Y930000D03*
Y920000D03*
X25000Y930000D03*
Y920000D03*
X15000Y980000D03*
Y970000D03*
Y960000D03*
Y950000D03*
Y940000D03*
X25000D03*
Y950000D03*
Y960000D03*
Y970000D03*
Y980000D03*
X15000Y1030000D03*
Y1020000D03*
Y1010000D03*
Y1000000D03*
Y990000D03*
X25000D03*
Y1000000D03*
Y1010000D03*
Y1020000D03*
Y1040000D03*
Y1080000D03*
Y1070000D03*
Y1060000D03*
Y1050000D03*
Y1090000D03*
X19712Y1176350D03*
X25000Y1190400D03*
X17500Y1270000D03*
Y1260000D03*
Y1250000D03*
Y1240000D03*
Y1290000D03*
Y1280000D03*
Y1300000D03*
Y1310000D03*
Y1320000D03*
Y1360000D03*
Y1350000D03*
Y1330000D03*
Y1340000D03*
X60000Y20000D03*
Y40000D03*
X40000D03*
X60000Y60000D03*
X40000D03*
Y80000D03*
X60000D03*
Y100000D03*
X40000D03*
X60000Y120000D03*
X40000D03*
Y140000D03*
X60000D03*
Y160000D03*
X40000D03*
X38500Y202000D03*
X64487Y212761D03*
X56000Y237000D03*
X73437Y247161D03*
X49437Y254661D03*
X73437Y234661D03*
X62000Y276500D03*
X40000Y280000D03*
Y300000D03*
X60000D03*
Y320000D03*
X40000D03*
X60000Y340000D03*
X40000D03*
Y360000D03*
X35000Y446500D03*
X50500Y545500D03*
X58346Y516473D03*
X54088Y512336D03*
X39853Y512373D03*
X44111Y516510D03*
X47607Y527511D03*
X61834Y527515D03*
X72500Y508600D03*
X67500D03*
X40000Y560000D03*
Y580000D03*
Y600000D03*
Y620000D03*
X39000Y646000D03*
X30697Y679553D03*
X73437Y687417D03*
X64487Y665417D03*
X31043Y689115D03*
X30676Y663764D03*
X27143Y663071D03*
X27510Y688422D03*
X49500Y729000D03*
X49437Y707417D03*
X73437Y699917D03*
X31064Y704904D03*
X69500Y777000D03*
X51000Y755500D03*
X38500Y800500D03*
X39000Y834500D03*
X49000Y811000D03*
X51000Y846000D03*
X40000Y930000D03*
Y920000D03*
Y970000D03*
Y960000D03*
Y950000D03*
Y940000D03*
X67500Y961355D03*
X72500D03*
X50000Y1030000D03*
X70000Y1020000D03*
X40000Y1000000D03*
Y990000D03*
X50000Y1060000D03*
X47000Y1107500D03*
X64487Y1118173D03*
X30256Y1116731D03*
X30670Y1132472D03*
X39325Y1131400D03*
X26723Y1116038D03*
X30644Y1157871D03*
X49437Y1160173D03*
X73437Y1140173D03*
Y1152673D03*
X30623Y1142082D03*
X36848Y1173600D03*
X27090Y1141389D03*
X52000Y1186000D03*
X71500Y1205000D03*
X31500Y1224000D03*
X39425Y1226200D03*
X30000Y1190400D03*
X37225Y1230100D03*
X45800Y1306100D03*
X37500Y1360000D03*
X27500D03*
X45518Y1336366D03*
X41381Y1335567D03*
X80000Y80000D03*
X100000D03*
X120000D03*
Y100000D03*
X100000D03*
X80000D03*
X120000Y120000D03*
X100000D03*
X80000D03*
X86500Y157500D03*
X80000Y140000D03*
X118437Y141870D03*
X78500Y169500D03*
X111437Y195492D03*
X106937Y198543D03*
Y207992D03*
X111437Y165492D03*
Y180492D03*
X74937Y187461D03*
X92287Y194661D03*
X86637Y194861D03*
X95437Y176661D03*
Y181161D03*
X73937Y201661D03*
X78937D03*
X83937D03*
X88937D03*
X82000Y219000D03*
X111437Y245492D03*
Y235492D03*
X106937Y217441D03*
X111437Y265492D03*
Y275492D03*
X89237Y276861D03*
X95437Y300161D03*
X96000Y336500D03*
X80000Y320000D03*
Y340000D03*
X118437Y314114D03*
X89000Y403500D03*
X100000Y420000D03*
X120000Y440000D03*
X100000D03*
Y460000D03*
X120000D03*
Y480000D03*
X100000D03*
X120000Y500000D03*
X100000D03*
X104500Y515500D03*
X120500Y524000D03*
X86500Y522000D03*
X100000Y541500D03*
X87000Y541000D03*
X89000Y557500D03*
X108500Y572000D03*
X88000Y577500D03*
X118753Y594626D03*
X88000Y602500D03*
X111437Y648248D03*
Y633248D03*
Y618248D03*
X92287Y647417D03*
X86637Y647617D03*
X74937Y640217D03*
X85146Y621637D03*
X95437Y633917D03*
X81500Y672000D03*
X106937Y670197D03*
X111437Y688248D03*
X106937Y660748D03*
Y651299D03*
X88937Y654417D03*
X83937D03*
X78937D03*
X73937D03*
X111437Y728248D03*
Y718248D03*
Y698248D03*
X89237Y729617D03*
X75500Y757500D03*
X94000Y789000D03*
X118437Y766870D03*
X95437Y752917D03*
X89500Y802500D03*
X90000Y858000D03*
X100000Y880000D03*
Y900000D03*
X120000D03*
Y920000D03*
X100000D03*
X120000Y940000D03*
X111800Y987200D03*
Y983200D03*
X115800Y979200D03*
X119800Y971200D03*
Y975200D03*
Y979200D03*
X115800Y975200D03*
X119800Y987200D03*
Y983200D03*
X115800Y971200D03*
Y983200D03*
Y987200D03*
X119163Y959625D03*
X100000Y940000D03*
X101403Y981195D03*
X97063Y973225D03*
X98563Y977225D03*
X120000Y1025000D03*
X85000Y1020000D03*
X121914Y1003491D03*
X114100Y1002600D03*
X99700Y991400D03*
X108063Y991925D03*
X114300Y992362D03*
X104230Y992209D03*
X74000Y1074000D03*
X85000Y1060000D03*
X111437Y1071004D03*
X118437Y1047382D03*
X95537Y1082173D03*
X81000Y1124500D03*
X106937Y1122953D03*
Y1113504D03*
Y1104055D03*
X111437Y1101004D03*
Y1086004D03*
X92287Y1100173D03*
X86637Y1100373D03*
X74937Y1092973D03*
X95537Y1086673D03*
X73937Y1107173D03*
X78937D03*
X83937D03*
X88937D03*
X111437Y1171004D03*
Y1151004D03*
Y1141004D03*
X118437Y1219626D03*
X111437Y1181004D03*
X89237Y1182373D03*
X95437Y1205673D03*
X98500Y1241000D03*
X90000Y1252500D03*
X86000Y1282000D03*
X93000Y1319000D03*
X160000Y20000D03*
Y60000D03*
Y40000D03*
X140000D03*
Y60000D03*
X160000Y100000D03*
Y80000D03*
X140000D03*
Y100000D03*
X160000Y140000D03*
X140000D03*
X160000Y120000D03*
X140000D03*
X156500Y170500D03*
X130500Y211500D03*
X160500Y190000D03*
X160000Y180000D03*
X129000Y259000D03*
X142687Y237161D03*
Y248100D03*
X128000Y288500D03*
X160000Y280000D03*
X140000Y300000D03*
X160000D03*
X145437Y265561D03*
X140000Y320000D03*
X160000D03*
X140000Y440000D03*
Y460000D03*
Y480000D03*
Y500000D03*
X142500Y515500D03*
X150000Y526500D03*
X164107Y512331D03*
X168365Y516368D03*
X135000Y588000D03*
X153263Y568725D03*
X146263D03*
X144263Y573225D03*
X138763Y568725D03*
X148763Y576225D03*
X166400Y579400D03*
X168103Y569195D03*
X163763Y561225D03*
X165263Y565225D03*
X167000Y613000D03*
X147500Y605500D03*
X142687Y689917D03*
X135200Y738400D03*
X153705Y744831D03*
X153714Y720741D03*
X153757Y710653D03*
X140372Y732370D03*
X150253Y709713D03*
X145437Y717617D03*
X142687Y700767D03*
X140364Y749807D03*
X160000Y880000D03*
Y900000D03*
X140000Y920000D03*
X160000D03*
Y940000D03*
X140000D03*
X137163Y987125D03*
X130463Y983925D03*
X156000Y1032000D03*
X137063Y993725D03*
X145363Y997741D03*
X131110Y993257D03*
X134000Y1064000D03*
X153000Y1105000D03*
X132000Y1117000D03*
X148400Y1086900D03*
X142687Y1142673D03*
X154363Y1161725D03*
X153716Y1174793D03*
X145437Y1165673D03*
X150862Y1152723D03*
X142687Y1153523D03*
X170000Y1190500D03*
X153824Y1197248D03*
X153932Y1182940D03*
X148300Y1228800D03*
X148311Y1182767D03*
X135422Y1190937D03*
X140422D03*
X163500Y1345200D03*
X200000Y20000D03*
X180000D03*
X200000Y40000D03*
X180000D03*
X200000Y60000D03*
X180000D03*
Y80000D03*
X200000D03*
Y100000D03*
X180000D03*
Y120000D03*
X200000D03*
Y140000D03*
X180000D03*
X216500Y194756D03*
X210849Y194861D03*
X199149Y187461D03*
X188699Y212561D03*
X198149Y201661D03*
X203149D03*
X208149D03*
X213149D03*
X206000Y219000D03*
X180500Y237000D03*
X197649Y234661D03*
X173649Y254661D03*
X197649Y247161D03*
X180000Y300000D03*
X213449Y276861D03*
X180000Y320000D03*
Y340000D03*
X200000D03*
X178342Y512294D03*
X182600Y516331D03*
X171861Y527469D03*
X186088Y527473D03*
X196712Y508600D03*
X191712D03*
X210263Y546725D03*
X188614Y591491D03*
X182500Y559200D03*
Y571200D03*
Y575200D03*
X178500D03*
Y571200D03*
X182500Y567200D03*
X186500Y559200D03*
Y563200D03*
Y567200D03*
X182500Y563200D03*
X186500Y575200D03*
Y571200D03*
X180800Y590600D03*
X207313Y598113D03*
X203763Y581725D03*
X212063Y585741D03*
X197810Y581257D03*
X174763Y579925D03*
X203863Y575125D03*
X181000Y580362D03*
X170930Y580209D03*
X197163Y571925D03*
X210000Y644000D03*
X216499Y636917D03*
X199149Y631217D03*
X210849Y638617D03*
X206000Y672000D03*
X197649Y687417D03*
X198149Y654417D03*
X203149D03*
X208149D03*
X213149D03*
X213449Y729617D03*
X173649Y707417D03*
X197649Y699917D03*
X180000Y860000D03*
Y880000D03*
Y920000D03*
Y900000D03*
X199900Y923200D03*
X188706Y941328D03*
X194206D03*
X184017Y951112D03*
Y945612D03*
X198463Y945525D03*
Y951025D03*
X216712Y961155D03*
X184295Y1009469D03*
Y1014969D03*
X198741Y1014882D03*
Y1009382D03*
X188552Y1019166D03*
X215563Y1001225D03*
X203563D03*
X207563D03*
X211563D03*
X194052Y1019166D03*
X211000Y1065000D03*
X203500Y1124500D03*
X216499Y1100173D03*
X210849Y1100373D03*
X199149Y1092973D03*
X188399Y1113873D03*
X195100Y1096800D03*
X198149Y1107173D03*
X203149D03*
X208149D03*
X213149D03*
X175000Y1143000D03*
X173649Y1160173D03*
X193423Y1140945D03*
X197649Y1152673D03*
X213449Y1182373D03*
X181000Y1261000D03*
X190000Y1320000D03*
X200000D03*
X210000D03*
Y1300000D03*
Y1310000D03*
X200000D03*
X190000D03*
X260000Y20000D03*
X220000D03*
X240000D03*
X260000Y60000D03*
Y40000D03*
X240000D03*
X220000D03*
Y60000D03*
X240000D03*
X260000Y100000D03*
Y80000D03*
X240000D03*
X220000D03*
Y100000D03*
X240000D03*
X260000Y140000D03*
Y120000D03*
X240000D03*
X220000D03*
X242649Y141870D03*
X262000Y209000D03*
X235649Y195492D03*
X231991Y198543D03*
X231149Y207992D03*
X235649Y165492D03*
Y180492D03*
X219749Y176661D03*
Y181361D03*
X253000Y260000D03*
X266899Y237161D03*
X235649Y245492D03*
Y235492D03*
X231149Y217441D03*
X266899Y248011D03*
X255000Y280000D03*
X235649Y265492D03*
Y275492D03*
X219649Y300161D03*
X242649Y314114D03*
X220000Y360000D03*
X240000Y380000D03*
X220000D03*
Y400000D03*
X240000D03*
Y420000D03*
X220000D03*
Y440000D03*
X240000D03*
Y460000D03*
X220000D03*
Y480000D03*
X240000D03*
Y500000D03*
X220000D03*
X265392Y539225D03*
Y533725D03*
X250586Y533920D03*
Y539420D03*
X260703Y529168D03*
X255203D03*
X220000Y520000D03*
X265275Y596896D03*
X250974Y597308D03*
X243051Y594626D03*
X265275Y602396D03*
X250974Y602808D03*
X255410Y607833D03*
X235649Y648248D03*
Y633248D03*
Y618248D03*
X260910Y607833D03*
X219749Y618917D03*
Y623417D03*
X255500Y664500D03*
X231149Y670197D03*
X235649Y688248D03*
X231149Y660748D03*
Y651299D03*
X266899Y689917D03*
X235649Y728248D03*
Y718248D03*
Y698248D03*
X264739Y732114D03*
X258600Y715500D03*
X266899Y700767D03*
X242649Y766870D03*
X219649Y752917D03*
X248500Y788500D03*
X264731Y749551D03*
X225000Y840000D03*
X245000D03*
X265000Y795000D03*
X225000Y815000D03*
Y880000D03*
X245000D03*
X225000Y860000D03*
X245000D03*
X225000Y900000D03*
X245000D03*
X223100Y920600D03*
X245000Y940000D03*
X239000Y985600D03*
X221712Y961155D03*
X263000Y1023000D03*
X219563Y1001225D03*
X223563D03*
X252100Y990100D03*
X244600Y1004600D03*
X261100Y1005700D03*
X227063Y994925D03*
X263000Y1047000D03*
X235649Y1071004D03*
X242649Y1047382D03*
X219749Y1082173D03*
X231149Y1122953D03*
Y1113504D03*
Y1104055D03*
X235649Y1101004D03*
Y1086004D03*
X264864Y1120500D03*
X219749Y1086873D03*
X235649Y1171004D03*
Y1151004D03*
X235300Y1142700D03*
X266899Y1141173D03*
X255000Y1207500D03*
X242649Y1219626D03*
X235649Y1181004D03*
X219649Y1205673D03*
X264594Y1190768D03*
X259594D03*
X257000Y1253000D03*
X220000Y1270000D03*
Y1320000D03*
X230000D03*
X240000D03*
X250000D03*
X260000D03*
X220000Y1280000D03*
X230000D03*
X250000Y1290000D03*
X240000D03*
X230000D03*
X220000D03*
Y1300000D03*
X230000D03*
X240000D03*
X250000D03*
X260000D03*
Y1310000D03*
X250000D03*
X240000D03*
X230000D03*
X220000D03*
X300000Y20000D03*
X280000D03*
X300000Y40000D03*
X280000Y60000D03*
Y40000D03*
X312079Y68379D03*
X303029Y68429D03*
X280000Y100000D03*
Y80000D03*
X313312Y98705D03*
X312355Y72855D03*
X313628Y112926D03*
X303000Y73500D03*
X280000Y140000D03*
Y120000D03*
X314370Y118452D03*
X314439Y133669D03*
X270000Y179500D03*
X285500Y189500D03*
X283000Y181000D03*
X314329Y212420D03*
X304500Y237000D03*
X297862Y254661D03*
X300000Y300000D03*
X269649Y266261D03*
X300000Y320000D03*
Y340000D03*
X295000Y400000D03*
Y440000D03*
X291601Y418503D03*
X295000Y460000D03*
X292153Y486059D03*
X306388Y486022D03*
X302513Y512294D03*
X306771Y516331D03*
X292536Y516368D03*
X288278Y512331D03*
X296032Y527469D03*
X310259Y527473D03*
X282263Y589225D03*
X270263D03*
X274263D03*
X286263D03*
X290263D03*
X278263D03*
X293763Y582925D03*
X277000Y618500D03*
X275000Y647000D03*
X294500Y607500D03*
X284000D03*
X312912Y665417D03*
X277972Y744575D03*
X297862Y707417D03*
X277981Y720485D03*
X278024Y710397D03*
X274520Y709457D03*
X286000Y810500D03*
X268100Y982300D03*
X273300Y981700D03*
X280800Y1011900D03*
X281200Y1033000D03*
X305200Y1068400D03*
X295200Y1078400D03*
Y1058400D03*
X271100Y1063200D03*
X281500Y1036744D03*
X281000Y1105000D03*
X312912Y1118273D03*
X304500Y1142500D03*
X302452Y1165162D03*
X278577Y1161725D03*
X277930Y1175001D03*
X269649Y1165673D03*
X275385Y1152596D03*
X271165Y1147172D03*
X306000Y1182500D03*
X278076Y1197355D03*
X278146Y1182940D03*
X315500Y1216700D03*
X276100Y1229100D03*
X273243Y1182915D03*
X286925Y1201945D03*
X301000Y1231000D03*
X295900Y1339700D03*
X296100Y1335100D03*
X279900Y1328300D03*
X283700D03*
X286100Y1349659D03*
X292600Y1337367D03*
X289510Y1342259D03*
X360000Y20000D03*
X340000D03*
X320000D03*
X360000Y40000D03*
X340000D03*
X320000D03*
X355200Y58400D03*
X346245Y58745D03*
X354100Y62100D03*
X322500Y68345D03*
X334845Y58745D03*
X317812Y98905D03*
X353001Y81799D03*
X351000Y70700D03*
X322545Y72845D03*
X361776Y70842D03*
X335081Y104081D03*
X339219Y95188D03*
X339914Y82415D03*
X344304Y82439D03*
X345321Y102400D03*
X347647Y95614D03*
X353001Y114815D03*
X347881Y114881D03*
X351416Y95788D03*
X337641Y114910D03*
X334947Y94605D03*
X342761Y114861D03*
X328000Y150500D03*
X333021Y129679D03*
X350441Y117541D03*
X337721Y129821D03*
X323813Y118512D03*
X341114Y123622D03*
X345321Y118921D03*
X323813Y133722D03*
X359862Y165492D03*
Y180492D03*
Y195492D03*
X355362Y198543D03*
Y207992D03*
X323362Y187461D03*
X340712Y194661D03*
X335062Y194861D03*
X344062Y176461D03*
X343962Y181161D03*
X322362Y201661D03*
X327362D03*
X332362D03*
X337362D03*
X333500Y219000D03*
X359862Y245492D03*
Y235492D03*
X355362Y217441D03*
X321862Y234661D03*
Y247161D03*
X359862Y265492D03*
Y275492D03*
X337662Y276861D03*
X343862Y300161D03*
X352000Y331000D03*
X320000Y340000D03*
X320474Y379474D03*
X316534D03*
X320474Y363234D03*
X316534D03*
X350000Y440000D03*
X330000D03*
X350000Y500000D03*
Y480000D03*
Y460000D03*
X330000D03*
X320925Y485385D03*
X315925D03*
X330000Y540000D03*
X350000D03*
Y520000D03*
X320925Y508600D03*
X315925D03*
X333000Y560000D03*
Y580000D03*
X350000Y560000D03*
X333000Y604000D03*
X359862Y648248D03*
Y633248D03*
Y618248D03*
X340712Y647517D03*
X335062Y647617D03*
X323362Y640217D03*
X333682Y621858D03*
X343862Y633917D03*
X330000Y672000D03*
X355362Y670197D03*
X359862Y688248D03*
X355362Y660748D03*
Y651299D03*
X321862Y687417D03*
X322362Y654417D03*
X327362D03*
X332362D03*
X337362D03*
X359862Y728248D03*
Y718248D03*
Y698248D03*
X337662Y729617D03*
X321862Y699917D03*
X355000Y780500D03*
X320000Y750000D03*
X330000Y770000D03*
X347000Y788500D03*
X343862Y752917D03*
X320474Y832229D03*
X316534D03*
X361500Y901500D03*
X330000Y900000D03*
X320925Y938140D03*
X315600Y933600D03*
X335300Y926900D03*
X360000Y960000D03*
Y940000D03*
X330000Y960000D03*
X337100Y972100D03*
X320925Y961355D03*
X315925D03*
X322000Y988500D03*
X362000Y1017000D03*
X344737Y995637D03*
X350673Y1031200D03*
X328000Y1061000D03*
X359862Y1071004D03*
X344062Y1082073D03*
X355362Y1122953D03*
Y1113504D03*
Y1104055D03*
X359862Y1101004D03*
Y1086004D03*
X340812Y1100273D03*
X335062Y1100373D03*
X323362Y1092973D03*
X344062Y1086773D03*
X322362Y1107173D03*
X327362D03*
X332362D03*
X337362D03*
X358518Y1171114D03*
X359862Y1151004D03*
Y1141004D03*
X321862Y1140173D03*
Y1152673D03*
X331679Y1175800D03*
X327500Y1197000D03*
X359862Y1181004D03*
X337662Y1182373D03*
X343862Y1205673D03*
X353000Y1231000D03*
X330000Y1302000D03*
X380000Y20000D03*
Y60000D03*
Y40000D03*
X401000Y89000D03*
X400000Y80000D03*
X365162Y88731D03*
Y77731D03*
X377144Y84720D03*
X377944Y95929D03*
X388500Y153500D03*
X395500Y160500D03*
X366862Y141870D03*
X386000Y209000D03*
X390312Y237161D03*
X390412Y248011D03*
X389000Y289000D03*
X386800Y263800D03*
X385500Y313000D03*
X366862Y314114D03*
X390000Y500000D03*
X370000D03*
X390000Y540000D03*
Y520000D03*
X370000D03*
Y540000D03*
X389000Y594500D03*
X390000Y560000D03*
X370000D03*
X366862Y594626D03*
X395000Y631000D03*
X388000Y607000D03*
X410000Y692500D03*
X379000Y664000D03*
X391112Y689917D03*
X402129Y744503D03*
X388796Y732042D03*
X402138Y720413D03*
X402181Y710325D03*
X393862Y719917D03*
X398677Y709385D03*
X391112Y700767D03*
X402500Y780500D03*
X366862Y766870D03*
X388788Y749479D03*
X407714Y761291D03*
X398254Y763517D03*
X397000Y911000D03*
X380000Y960000D03*
Y940000D03*
X393500Y988500D03*
Y1017000D03*
X408672Y1008038D03*
X390000Y1055000D03*
X366862Y1047382D03*
X388888Y1118173D03*
X391112Y1142673D03*
X399474Y1166787D03*
X385210Y1166347D03*
X393679Y1157480D03*
X383191Y1170203D03*
X391112Y1153500D03*
X366862Y1219626D03*
X406037Y1192706D03*
X402403Y1188312D03*
X398527Y1188659D03*
X383849Y1190833D03*
X388849Y1191148D03*
X398527Y1233336D03*
X437124Y212661D03*
X447574Y187461D03*
X446951Y213656D03*
X451951D03*
X456951D03*
X446074Y247161D03*
X422300Y254661D03*
X446074Y234661D03*
X441645Y288847D03*
Y284647D03*
X456190Y354105D03*
X444687Y379474D03*
X440747D03*
X444687Y363234D03*
X440747D03*
X452800Y420912D03*
X418600Y445462D03*
X421700Y450200D03*
X445138Y487743D03*
X440138D03*
X447533Y475900D03*
X458679Y470700D03*
X450500Y459562D03*
X416303Y486022D03*
X430538Y485985D03*
X430000Y545500D03*
X460000Y540000D03*
X426663Y512257D03*
X430921Y516294D03*
X416686Y516331D03*
X412428Y512294D03*
X420182Y527432D03*
X434409Y527436D03*
X440138Y508600D03*
X445138D03*
X460000Y600000D03*
X445000D03*
X440000Y560000D03*
X460000D03*
X440000Y613000D03*
X459274Y647617D03*
X447574Y640217D03*
X457853Y622091D03*
X417000Y652500D03*
X454500Y672000D03*
X446074Y687417D03*
X437224Y665417D03*
X456574Y654417D03*
X451574D03*
X446574D03*
X452500Y744500D03*
X437500Y744000D03*
X422074Y707417D03*
X446074Y699917D03*
X455000Y780000D03*
X445000D03*
X440000Y760000D03*
X445000Y798000D03*
X444687Y832229D03*
X440747D03*
X444687Y816765D03*
X440747D03*
X445138Y938140D03*
X440138D03*
X435082Y915200D03*
X437600Y917800D03*
X445582Y925352D03*
X449137Y967757D03*
X440138Y961355D03*
X445138D03*
X428000Y988500D03*
X429613Y1017920D03*
X432657Y1015102D03*
X442600Y998300D03*
X413000Y1054200D03*
X442473Y1068726D03*
X447173D03*
X424000Y1105000D03*
X453473Y1089300D03*
X418500Y1176800D03*
X437104Y1160696D03*
X441400Y1169400D03*
X450500Y1208500D03*
X424000Y1206000D03*
X416900Y1221800D03*
X454500Y1248500D03*
X460000Y1320000D03*
X440000D03*
X460000Y1300000D03*
X412300Y1326200D03*
X415422Y1352000D03*
X422373Y1359747D03*
X418922Y1356522D03*
X476319Y144481D03*
X506750Y165324D03*
X480159Y201245D03*
X500184Y200328D03*
X497785Y178034D03*
X478306Y195593D03*
X461122Y194861D03*
X462200Y173109D03*
X468472Y182441D03*
X461951Y213656D03*
X484074Y245492D03*
X478651Y220734D03*
X484074Y235492D03*
Y275492D03*
X481174Y265492D03*
X461874Y276861D03*
X468074Y300161D03*
X491074Y314114D03*
X470000Y400000D03*
Y380000D03*
Y430000D03*
X465000Y491000D03*
X462133Y473300D03*
X481533Y480875D03*
X506746Y512331D03*
X497351Y531531D03*
X501023Y534941D03*
X499000Y553000D03*
X491074Y594626D03*
X472022Y582062D03*
X484074Y648248D03*
Y633248D03*
Y618248D03*
X464924Y647417D03*
X468174Y633917D03*
X479574Y670197D03*
X484074Y688248D03*
X479574Y660748D03*
Y651299D03*
X461574Y654417D03*
X484074Y728248D03*
Y718248D03*
Y698248D03*
X461874Y729617D03*
X461500Y769500D03*
X491074Y766870D03*
X468074Y752917D03*
X500000Y960000D03*
Y940000D03*
X480000Y960000D03*
Y940000D03*
X504000Y988500D03*
X462000D03*
X465200Y1018200D03*
X468000Y1047000D03*
X484074Y1071004D03*
X491074Y1047382D03*
X460673Y1071976D03*
X460873Y1077526D03*
X506500Y1051900D03*
X465346Y1122953D03*
X479574Y1113504D03*
Y1104055D03*
X484074Y1101004D03*
Y1086004D03*
X504724Y1118073D03*
X484074Y1171004D03*
Y1151004D03*
Y1141004D03*
X506700Y1141973D03*
X505874Y1134773D03*
X506700Y1145973D03*
X502500Y1211500D03*
X476373Y1219498D03*
X484074Y1181004D03*
X461874Y1182373D03*
X468074Y1205673D03*
X508103Y1190557D03*
X480000Y1320000D03*
X500000Y1300000D03*
X480000D03*
Y1280000D03*
X509180Y145419D03*
X539584Y184694D03*
X542155Y187543D03*
X519868Y242334D03*
X515324Y252511D03*
X515500Y301000D03*
X550987Y262810D03*
X553742Y267705D03*
X510700Y277200D03*
X548500Y343000D03*
X515000Y322500D03*
X534905Y354105D03*
X547500Y440000D03*
X539350Y487659D03*
X534350D03*
X510621Y486059D03*
X524856Y486022D03*
X520981Y512294D03*
X549279Y513331D03*
X525579Y538331D03*
X557279Y513331D03*
X525239Y516331D03*
X511004Y516368D03*
X518700Y548700D03*
X553279Y523331D03*
X514500Y524469D03*
X528727Y524973D03*
X553279Y513331D03*
X530130Y547167D03*
X534350Y508600D03*
X539350D03*
X540000Y583000D03*
Y600000D03*
X520000D03*
X533879Y566031D03*
X548767Y556819D03*
X520579Y553231D03*
X517499Y576931D03*
X557279Y570331D03*
X528000Y611000D03*
X532000Y623000D03*
X515324Y689917D03*
X526225Y744756D03*
X546287Y707417D03*
X512892Y732295D03*
X526277Y710578D03*
X526234Y720666D03*
X509996Y716996D03*
X522773Y709638D03*
X515324Y700667D03*
X509000Y772000D03*
X512884Y749732D03*
X555500Y852000D03*
X551500Y888000D03*
X523500Y883500D03*
X525000Y937000D03*
X525500Y967000D03*
X530800Y1028300D03*
X515800Y1028000D03*
X523000Y1045000D03*
X528500Y1073500D03*
X556022Y1042817D03*
X552436Y1042494D03*
X514474Y1107073D03*
X519474D03*
X524474D03*
X529474D03*
X546287Y1160173D03*
X535320Y1152771D03*
X534874Y1139774D03*
X526523Y1177122D03*
X526501Y1166546D03*
X509037Y1136700D03*
X524828Y1159231D03*
X526388Y1197747D03*
X526367Y1183111D03*
X522867Y1190284D03*
X513103Y1190557D03*
X522867Y1231097D03*
X539000Y1309000D03*
X520600Y1324100D03*
X536000Y1359826D03*
X541362D03*
X518397Y1360000D03*
X512900Y1345600D03*
X553587Y1346026D03*
X527000Y1340600D03*
X521500Y1342800D03*
X603787Y207992D03*
X604517Y196263D03*
X603697Y182091D03*
X586719Y196888D03*
X568687Y187660D03*
X583487Y194861D03*
X566271Y167387D03*
X592767Y179277D03*
X598236Y181981D03*
X582697Y200744D03*
X577697D03*
X572697D03*
X587697D03*
X588188Y216520D03*
X570287Y234661D03*
X563000Y217600D03*
X569009Y247887D03*
X592287Y300161D03*
X582758Y276861D03*
X590000Y342000D03*
X568899Y379474D03*
X564959D03*
X568899Y363234D03*
X564959D03*
X560000Y438500D03*
X594500Y462000D03*
X569529Y502127D03*
X575700Y528831D03*
X563279Y506731D03*
X602379Y547831D03*
X570779Y542831D03*
X568779Y512831D03*
X575779D03*
X593079Y516531D03*
Y512531D03*
X585479Y537731D03*
Y543994D03*
X572229Y520081D03*
X580279Y512831D03*
X592000Y595000D03*
X580000Y600000D03*
X560000D03*
X571408Y577450D03*
X584279Y577431D03*
X575779D03*
X579718D03*
X592779D03*
X588779D03*
X562279D03*
X567641Y577473D03*
X571529Y562951D03*
X579529D03*
X586000Y611000D03*
X589137Y647417D03*
X583487Y647617D03*
X571787Y640217D03*
X592387Y629417D03*
Y634017D03*
X579000Y672000D03*
X603787Y670197D03*
Y660748D03*
Y651299D03*
X570287Y687417D03*
X561437Y665417D03*
X585787Y654417D03*
X580787D03*
X575787D03*
X570787D03*
X559000Y741000D03*
X586087Y729617D03*
X570287Y699917D03*
X603000Y781000D03*
X592287Y752917D03*
X568899Y832229D03*
X564959D03*
X593365Y877358D03*
X592614Y882300D03*
X604000Y897000D03*
X592000Y900500D03*
X569350Y941640D03*
X564350D03*
X569350Y961355D03*
X564350D03*
X589500Y988000D03*
X571000D03*
X571400Y1000100D03*
X575000Y1057500D03*
X586500Y1061500D03*
X586000Y1046500D03*
X575000Y1046000D03*
X592387Y1082173D03*
X561337Y1120873D03*
X583487Y1100373D03*
X571787Y1092973D03*
X589137Y1100173D03*
X603787Y1122953D03*
Y1113504D03*
Y1104055D03*
X592387Y1086873D03*
X570787Y1107173D03*
X575787D03*
X580787D03*
X585787D03*
X570287Y1140173D03*
Y1152673D03*
X600640Y1171000D03*
X567500Y1189500D03*
X586087Y1182373D03*
X592287Y1205673D03*
X592400Y1214456D03*
X590000Y1247000D03*
X613500Y66000D03*
X634500Y77000D03*
X629024Y107633D03*
X607929Y112329D03*
X619171D03*
X614967Y134777D03*
X606718Y168580D03*
X639537Y237161D03*
X608287Y245492D03*
Y235492D03*
X639537Y248011D03*
X649500Y285000D03*
X608287Y275492D03*
X607961Y263934D03*
X642287Y266461D03*
X650000Y322500D03*
X615287Y314114D03*
X649000Y429500D03*
X652663Y502400D03*
X647663D03*
X612000Y502300D03*
X624028Y503558D03*
X638263Y503494D03*
X643000Y549500D03*
X620153Y511994D03*
X634388Y511957D03*
X615100Y513287D03*
X638646Y515994D03*
X624411Y516031D03*
X615119Y551586D03*
X627000Y538581D03*
Y542909D03*
X609334Y538306D03*
Y543306D03*
X627863Y522000D03*
X642509Y520667D03*
X652663Y516600D03*
X647663D03*
X615287Y594626D03*
X615147Y565956D03*
X637213Y582155D03*
X608287Y648248D03*
Y633248D03*
Y618248D03*
Y688248D03*
X639537Y689917D03*
X650659Y744673D03*
X608287Y728248D03*
Y718248D03*
Y698248D03*
X637326Y732212D03*
X650668Y720583D03*
X650711Y710495D03*
X642287Y719817D03*
X647207Y709555D03*
X639537Y700767D03*
X631500Y774000D03*
X615287Y766870D03*
X637318Y749649D03*
X642000Y889500D03*
X632000Y936000D03*
X654000Y911000D03*
X646500Y898500D03*
X634000Y988000D03*
X638500Y1046500D03*
X608287Y1071004D03*
X615287Y1047382D03*
X645200Y1067800D03*
X608287Y1101004D03*
Y1086004D03*
X643000Y1146173D03*
X608287Y1171004D03*
Y1151004D03*
Y1141004D03*
X651216Y1164051D03*
X636803Y1167864D03*
X642942Y1156818D03*
X632603Y1136225D03*
X647716Y1154150D03*
X639537Y1153523D03*
X615238Y1218951D03*
X608287Y1181004D03*
X650644Y1197038D03*
X650626Y1182447D03*
X627632Y1217300D03*
X647126Y1189513D03*
X632316Y1190474D03*
X637316D03*
X700000Y60000D03*
X675000Y75500D03*
X697457Y107247D03*
X697483Y111500D03*
X661965Y106177D03*
X687566Y109568D03*
X663449Y115606D03*
X690807Y103298D03*
X658500Y184500D03*
X695137Y189130D03*
X685545Y212806D03*
X699950Y200846D03*
X694950D03*
X689426Y236628D03*
X694500Y247161D03*
X670500Y254661D03*
X673500Y344000D03*
X689232Y355251D03*
X693112Y385976D03*
X689172D03*
Y358978D03*
X698500Y415500D03*
X695500Y462500D03*
X670000Y531500D03*
X658646Y515180D03*
X696787Y580633D03*
X658681Y571798D03*
X654681D03*
X683341Y580479D03*
X689747D03*
X696000Y641717D03*
X694500Y687417D03*
X685550Y665417D03*
X700000Y654417D03*
X695000D03*
X670500Y707417D03*
X694500Y699917D03*
X691500Y778000D03*
X692500Y790500D03*
X678500Y776500D03*
X673500Y752000D03*
X658574Y930100D03*
X677457Y944796D03*
X688563Y961355D03*
X693563D03*
X663800Y1018300D03*
X682200Y1026500D03*
X674300Y1001620D03*
X696000Y1092973D03*
X685250Y1113673D03*
X695000Y1107173D03*
X700000D03*
X667700Y1160173D03*
X694500Y1140173D03*
X692671Y1152747D03*
X668000Y1195000D03*
X680500Y1208500D03*
X698500Y1306500D03*
X664000Y1278100D03*
X673000Y1354100D03*
X740000Y40000D03*
X720000D03*
Y60000D03*
X740000D03*
X724645Y138941D03*
X732500Y180492D03*
Y165492D03*
X728000Y207992D03*
Y198543D03*
X732100Y198373D03*
X707700Y194861D03*
X713350Y194661D03*
X747242Y197553D03*
X717188Y176461D03*
X716600Y181161D03*
X709950Y200846D03*
X704950D03*
X728000Y217441D03*
X732500Y245492D03*
X731048Y238563D03*
X738361Y306612D03*
X732500Y275492D03*
Y265492D03*
X710300Y276861D03*
X716500Y300161D03*
X724000Y338500D03*
X748000Y368500D03*
X726000Y369000D03*
X732000Y374500D03*
Y383000D03*
X748500Y409000D03*
X721500Y462500D03*
X727500Y476000D03*
X705348Y478425D03*
X724000Y583500D03*
X702500Y563000D03*
X739500Y594626D03*
X732500Y648248D03*
Y633248D03*
Y618248D03*
X713350Y647417D03*
X716600Y629417D03*
Y633917D03*
X704500Y672000D03*
X728000Y670197D03*
X732500Y688248D03*
X728000Y660748D03*
Y651299D03*
X707700Y649117D03*
X710000Y654417D03*
X705000D03*
X732500Y728248D03*
Y718248D03*
Y698248D03*
X710300Y729617D03*
X748000Y783000D03*
X739500Y766870D03*
X716500Y752917D03*
X745000Y833000D03*
X704500Y795000D03*
X730882Y888502D03*
X716233Y868219D03*
X733422Y857828D03*
X708683Y876958D03*
X747656Y876717D03*
X724283Y860689D03*
X737984Y861689D03*
X741883Y861389D03*
X709500Y894500D03*
X733883Y935689D03*
X736883Y938689D03*
Y929189D03*
Y933689D03*
X747383Y924689D03*
X733883Y940689D03*
X736462Y948996D03*
X736883Y943189D03*
X712000Y1046000D03*
X732500Y1071004D03*
X739500Y1047382D03*
X716600Y1081973D03*
X728000Y1122953D03*
Y1113504D03*
Y1104055D03*
X732500Y1101004D03*
Y1086004D03*
X713350Y1100173D03*
X707700Y1100373D03*
X716600Y1086673D03*
X705000Y1107173D03*
X710000D03*
X716000Y1136000D03*
X732500Y1171004D03*
Y1151004D03*
Y1141004D03*
X739500Y1219626D03*
X732500Y1181004D03*
X710300Y1182373D03*
X716500Y1205673D03*
X728174Y1275611D03*
X725678Y1272799D03*
X722790Y1270557D03*
X720446Y1267427D03*
X748500Y1287500D03*
X731500Y1277811D03*
X789045Y11615D03*
X780000Y40000D03*
X760000D03*
Y60000D03*
X780000D03*
X757020Y159692D03*
X752950Y213450D03*
X758619Y168537D03*
X767405Y210364D03*
X763188Y172500D03*
X771500Y311000D03*
X789739Y365493D03*
X764000Y439500D03*
X767500Y463500D03*
X772000Y479500D03*
X787000Y514000D03*
X798140Y630220D03*
X798210Y626440D03*
X798367Y622400D03*
X751750Y685300D03*
X754500Y668741D03*
X755000Y677700D03*
X793000Y828000D03*
Y851000D03*
X757664Y868974D03*
X753883Y929689D03*
Y937689D03*
X763883Y907689D03*
X755883D03*
X750883Y903689D03*
X753893Y912630D03*
X753883Y945689D03*
X776400Y956500D03*
X780800Y959300D03*
X778000Y988500D03*
X762500D03*
X786800Y1016000D03*
X784000Y1024000D03*
X763000Y1075000D03*
X759500Y1056100D03*
X756250Y1140250D03*
X779535Y1180469D03*
X792263Y1178661D03*
Y1174461D03*
Y1170261D03*
X752500Y1167500D03*
X756250Y1151750D03*
X752000Y1197500D03*
X756000Y1225500D03*
X784544Y1210178D03*
Y1205978D03*
X779535Y1193469D03*
Y1189269D03*
Y1184669D03*
X797177Y1189537D03*
X797225Y1185337D03*
X792263Y1182861D03*
X770000Y1231500D03*
X769500Y1283500D03*
X792336Y1319537D03*
X782230Y1323670D03*
X769728Y1325747D03*
X785340Y1320410D03*
X789549Y1322310D03*
X777009Y1322690D03*
X781000Y1373000D03*
X781290Y1328490D03*
X772900Y1328550D03*
X790290Y1328410D03*
X785640Y1328370D03*
X784000Y1443000D03*
X796848Y1469724D03*
X829921Y-458D03*
X825984D03*
X833724Y-3346D03*
X833671Y254D03*
X806299Y-458D03*
X802362D03*
X814173D03*
X810236D03*
X822047D03*
X818110D03*
X845661Y-3642D03*
X843463Y530D03*
X802102Y51075D03*
X799102Y48575D03*
X802102Y46075D03*
X799102Y43575D03*
X802102Y41075D03*
X845961Y61762D03*
Y56762D03*
Y52762D03*
X838521Y41568D03*
X838043Y37217D03*
X806314Y35952D03*
X802350Y35923D03*
X842470Y41295D03*
X841733Y36654D03*
X818300Y39845D03*
X814300D03*
Y43845D03*
X818300D03*
X846000Y116500D03*
X811500Y372000D03*
X800000Y400000D03*
X811500Y469500D03*
X846400Y469300D03*
Y473900D03*
X839000Y541000D03*
X839500Y508500D03*
Y560000D03*
X800867Y619400D03*
X803367Y622400D03*
X827500Y922500D03*
X827000Y1168000D03*
X802036Y1164244D03*
X803438Y1139700D03*
X802500Y1194500D03*
X807500D03*
X812500D03*
X810000Y1191500D03*
X805000D03*
X806952Y1460496D03*
X806568Y1464275D03*
X802433Y1461619D03*
X800900Y1465234D03*
X800462Y1469231D03*
X839414Y1520763D03*
X834813Y1528889D03*
X834974Y1533243D03*
X882000Y-105500D03*
X885046Y20384D03*
X886322Y69D03*
X867080Y393D03*
X886427Y3802D03*
X873892Y287D03*
X886418Y-7350D03*
X849484Y649D03*
X886351Y-3735D03*
X857513Y659D03*
X861101Y66680D03*
X862099Y61626D03*
Y56626D03*
X861961Y52762D03*
X852769Y66957D03*
X848769D03*
X856769D03*
X853961Y52762D03*
X849961D03*
X857961D03*
X874244Y37026D03*
Y44935D03*
X885448Y37380D03*
X881750Y37397D03*
X858496Y37121D03*
X854180Y36996D03*
X852995Y40965D03*
X856995D03*
X852769Y74957D03*
X856769D03*
X861142Y71026D03*
X852810Y71303D03*
X856810D03*
X853900Y89701D03*
X888500Y260500D03*
X872796Y251714D03*
X850500Y266000D03*
X866000Y315000D03*
X881549Y326304D03*
X890982Y349498D03*
X874800Y355798D03*
X856500Y373000D03*
X858632Y399200D03*
X855032D03*
Y395600D03*
X858632D03*
X855032Y392000D03*
X858632D03*
X852832Y406400D03*
Y402800D03*
X856432Y406400D03*
Y402800D03*
X887100Y359100D03*
X887500Y378495D03*
X874807Y375193D03*
X852832Y410000D03*
X856432D03*
X866276Y454900D03*
X866317Y446725D03*
X857300Y454300D03*
X862000Y453600D03*
X852000Y454200D03*
X866321Y451300D03*
X855500Y499500D03*
X871487Y463589D03*
X878500Y476000D03*
X878193Y467707D03*
X866278Y459562D03*
X870600Y476900D03*
X851800Y477200D03*
X860092Y542405D03*
X867500Y643000D03*
X877000Y664500D03*
X868500Y665000D03*
X868100Y685600D03*
X871700D03*
X875300D03*
X884600Y688800D03*
X881000D03*
X877400D03*
X891000Y743500D03*
X870500Y762500D03*
X885600Y824400D03*
X870163Y836153D03*
X865663Y834403D03*
X867663Y818831D03*
X887600Y811900D03*
X891200Y838200D03*
X878673Y804527D03*
X874569Y811300D03*
X885882Y861618D03*
X894965Y843500D03*
X877673Y868873D03*
X888962Y843262D03*
X873647Y861653D03*
X882333Y896320D03*
X895616Y985932D03*
X863800Y1309876D03*
X885301Y1358557D03*
X884746Y1350438D03*
X873495Y1370213D03*
X885300Y1371050D03*
X872164Y1350464D03*
X873259Y1365805D03*
X872181Y1354764D03*
X886792Y1404100D03*
X873918Y1411149D03*
X873800Y1418200D03*
X871432Y1420932D03*
X874900Y1421900D03*
X877406Y1419124D03*
X875740Y1415070D03*
X882226Y1404197D03*
X873694Y1404575D03*
X873700Y1375746D03*
X873570Y1380401D03*
X877300Y1432400D03*
X886500Y1432500D03*
X872192Y1424492D03*
X882000Y1432600D03*
X870921Y1432300D03*
X893158Y1516542D03*
X893050Y1489500D03*
X868791Y1478782D03*
X888800Y1493500D03*
X863851Y1501681D03*
X877828Y1500379D03*
X892966Y1508549D03*
X893036Y1512600D03*
X877946Y1496527D03*
X876096Y1505499D03*
X889002Y1489638D03*
X873972Y1472467D03*
X873922Y1477766D03*
X860179Y1491170D03*
X892682Y1520718D03*
X855092Y1535821D03*
X866621Y1544206D03*
X893020Y1566530D03*
X876200Y1553900D03*
X892700Y1543900D03*
X892558Y1528458D03*
X889300Y1551000D03*
X876190Y1537187D03*
X876100Y1549000D03*
X876200Y1558400D03*
X892700Y1524700D03*
X848551Y1542440D03*
X910500Y-137500D03*
X928600Y-115200D03*
X902000Y-58000D03*
X922687Y93D03*
X928138Y-8453D03*
X909000Y89000D03*
X898000Y133000D03*
X911000Y305500D03*
X898000Y268000D03*
X942000Y752850D03*
X897000Y839000D03*
X915000Y879000D03*
X903000Y842500D03*
X926185Y928342D03*
X924974Y933041D03*
X895869Y932822D03*
X914876Y901029D03*
X937621Y915324D03*
X920810Y902210D03*
X928100Y900650D03*
X900615Y909723D03*
X902571Y906534D03*
X903368Y934568D03*
X904594Y931141D03*
X916204Y938572D03*
X917550Y934742D03*
X901540Y937712D03*
X896679Y927505D03*
X896420Y916712D03*
X898468Y912970D03*
X931085Y936172D03*
X941274Y900845D03*
X924563Y962945D03*
X919759Y970868D03*
X938009Y987330D03*
X941868Y952101D03*
X934142Y974344D03*
X939481Y980230D03*
X912994Y971921D03*
X910397Y979189D03*
X902991Y982230D03*
X909826Y982874D03*
X905271Y974586D03*
X899846Y971468D03*
X898617Y975434D03*
X895837Y978389D03*
X896629Y982285D03*
X935623Y971054D03*
X898920Y1020000D03*
X916446Y1035438D03*
X941640Y995820D03*
X904601Y998556D03*
X910040Y1006613D03*
X911807Y1002342D03*
X919656Y998764D03*
X939544Y1003485D03*
X903442Y1003265D03*
X896371Y1002112D03*
X936378Y1035722D03*
X929257Y1035883D03*
X920770Y1067389D03*
X921149Y1062424D03*
X914948Y1063255D03*
X908477Y1061823D03*
X910387Y1055344D03*
X904875Y1051177D03*
X906000Y1222000D03*
X924500Y1236000D03*
X942925Y1369010D03*
X928384Y1346435D03*
X932559Y1360137D03*
X928439Y1360167D03*
X932564Y1346100D03*
X896500Y1341800D03*
X936959Y1360143D03*
X896212Y1345788D03*
X932294Y1379995D03*
X928194D03*
X895900Y1390100D03*
X896200Y1386000D03*
X896100Y1393800D03*
X896200Y1397900D03*
Y1405300D03*
X896100Y1401600D03*
X923829Y1389012D03*
X936994Y1379895D03*
X927601Y1384433D03*
X923486Y1384268D03*
X904941Y1456941D03*
X906600Y1461600D03*
X909400Y1459200D03*
X910000Y1464900D03*
X905500Y1467161D03*
X932500Y1493200D03*
X926500Y1499700D03*
X918500D03*
X938000Y1499200D03*
X908742Y1477427D03*
X908542Y1481127D03*
X922500Y1509700D03*
X906000Y1543700D03*
X918505Y1530405D03*
X918800Y1534500D03*
X941000Y1564200D03*
X937000D03*
X926500Y1556700D03*
X931500Y1564200D03*
X913250Y1547700D03*
X940000Y1529200D03*
X940750Y1549200D03*
X900000Y1526500D03*
X897400Y1574000D03*
X897038Y1577600D03*
X911516Y1573202D03*
X911616Y1576802D03*
X911710Y1582375D03*
X911094Y1585923D03*
X924059Y1647700D03*
X986713Y-115570D03*
X971713D03*
X981700Y-115500D03*
X976713Y-115570D03*
X991713Y-115413D03*
X989316Y-94984D03*
X992185Y-54411D03*
X989050Y-70850D03*
X975500Y11500D03*
X974000Y402000D03*
X985688Y362549D03*
X974000Y523000D03*
X985500Y613500D03*
X978000Y677000D03*
X977794Y695103D03*
X952200Y742600D03*
X957100Y742900D03*
X977622Y699464D03*
X953200Y736700D03*
X956900Y737600D03*
X949048Y755225D03*
X952476Y753652D03*
X951300Y747900D03*
X956200Y748200D03*
X957320Y769818D03*
X947866Y763541D03*
X957629Y766231D03*
X952820Y769518D03*
X944500Y760750D03*
X962900Y905000D03*
X981580Y932678D03*
X953967Y933635D03*
X961100Y931640D03*
X960503Y936185D03*
X967583Y933607D03*
X968698Y928957D03*
X974484Y935078D03*
X976419Y931628D03*
X976460Y927891D03*
X981679Y936678D03*
X976213Y938846D03*
X966000Y937500D03*
X976580Y986180D03*
X948942Y974655D03*
X961134Y976191D03*
X959400Y960300D03*
X953013Y960147D03*
X947174Y957150D03*
X979020Y960000D03*
Y956200D03*
X973900Y960000D03*
Y956200D03*
X968780Y960000D03*
Y956200D03*
X987734Y979575D03*
X946138Y1006299D03*
X987970Y1004157D03*
X955700Y1030700D03*
X951200D03*
X946700D03*
X947759Y998726D03*
X961220Y1001600D03*
Y1005400D03*
X966340Y1001600D03*
Y1005400D03*
X971460Y1001600D03*
Y1005400D03*
X974020Y1026200D03*
Y1022400D03*
X968900Y1026200D03*
Y1022400D03*
X963780Y1026200D03*
Y1022400D03*
X956600Y1001700D03*
Y1005700D03*
X977400Y1157900D03*
X964537Y1160310D03*
X958870Y1163617D03*
X962941Y1165929D03*
X967497Y1168802D03*
X957871Y1171219D03*
X963000Y1174427D03*
X969463Y1177599D03*
X972924Y1158033D03*
X954395Y1145604D03*
X977500Y1182300D03*
X982387Y1183598D03*
X962500Y1298500D03*
X947125Y1369010D03*
X951525Y1369107D03*
X955500Y1369000D03*
X944921Y1515200D03*
X988624Y1502923D03*
X951815Y1491459D03*
X946300Y1499300D03*
X969198Y1505851D03*
X969472Y1501978D03*
X975813Y1556916D03*
X953500Y1563200D03*
X962000Y1564200D03*
X958000D03*
X949000D03*
X945000D03*
X972001Y1533926D03*
X975813Y1545916D03*
X954700Y1524100D03*
Y1530363D03*
X974787Y1525100D03*
Y1529300D03*
X948750Y1549200D03*
X979963Y1545689D03*
X1034916Y-82413D03*
Y-87913D03*
X1011984Y-83066D03*
X1012174Y-88726D03*
X1004213Y-95837D03*
X998045Y-79300D03*
X993816Y-95184D03*
X1036713Y-115500D03*
X1015582Y-69800D03*
X1014800Y-62100D03*
X999300Y-64400D03*
X1009100Y-48600D03*
X1035000Y-66800D03*
X1022618Y-36900D03*
X1023300Y-44200D03*
X1032053Y-34953D03*
X1038712Y-34812D03*
X1007582Y-39418D03*
X1000300Y-74200D03*
X1032080Y-45980D03*
X1004082Y-38200D03*
X1000418Y-69982D03*
X993000Y-60600D03*
X1019118Y-34382D03*
X1019082Y-71000D03*
X1026717Y-11646D03*
X1021086Y-11682D03*
X1017600Y63600D03*
Y58900D03*
Y54200D03*
X1010650Y49950D03*
Y67650D03*
X993000Y108000D03*
X1036003Y93543D03*
X1038503Y97543D03*
X1033503D03*
Y102543D03*
Y107543D03*
Y112543D03*
X993000Y157000D03*
Y329000D03*
X1020250Y357188D03*
X998000Y378000D03*
X995000Y455000D03*
X1040180Y437510D03*
X995000Y488000D03*
X1018322Y545207D03*
X1018300Y550000D03*
X993000Y635000D03*
X1025000Y817000D03*
X1028472Y834829D03*
X1027063Y850703D03*
X1031563Y852453D03*
X1038215Y877191D03*
X1034271Y876911D03*
X1011100Y904600D03*
X1025000Y897700D03*
X1036431Y929752D03*
X1037083Y933300D03*
X1016842Y916445D03*
X1014891Y943357D03*
X1013713Y974651D03*
X997694Y974940D03*
X1035947Y948800D03*
X1025774Y1001538D03*
X992994Y1005740D03*
X1012494Y1033840D03*
X1028657Y1009103D03*
X1020654Y1023940D03*
X1018094Y1021240D03*
X1015534Y1023840D03*
X1007849Y1033743D03*
X996600D03*
X1012974Y1021240D03*
X1013700Y1007640D03*
X1009509Y1009850D03*
X1037282Y995028D03*
X1005294Y997940D03*
Y1001740D03*
X1010414Y997940D03*
Y1001740D03*
X1023214Y1007140D03*
X1007372Y1023832D03*
X1017194Y1033840D03*
X1018000Y1076500D03*
X1037000Y1067100D03*
X1032500D03*
X1017000Y1093950D03*
X1021200Y1094300D03*
X1031400Y1124700D03*
X1026900Y1129466D03*
X1022400Y1129183D03*
X1036160Y1095500D03*
Y1091700D03*
Y1111900D03*
X1019000Y1178000D03*
X1013400Y1137500D03*
X1021991Y1141526D03*
X1004294Y1137600D03*
X994923Y1137488D03*
X997500Y1192500D03*
X1006800Y1191200D03*
X995948Y1184250D03*
X1017354Y1196124D03*
X1021061Y1198543D03*
X1032500Y1248000D03*
X993500Y1317000D03*
X1016835Y1323916D03*
X1025335Y1324216D03*
X1031000Y1350500D03*
X1031474Y1354526D03*
X1016672Y1338228D03*
X1025284Y1341216D03*
X1025335Y1337616D03*
Y1330916D03*
X1016600Y1332000D03*
X1033000Y1416125D03*
X1028000Y1404700D03*
Y1411000D03*
X1031500Y1408000D03*
X1020854Y1455075D03*
X1016854D03*
X1065621Y-85082D03*
X1046713Y-115570D03*
X1076713D03*
X1084200Y-82300D03*
X1074400Y-81000D03*
X1051713Y-114887D03*
X1056713Y-115413D03*
X1086713Y-115570D03*
X1081713D03*
X1071713D03*
X1066713D03*
X1041713Y-115465D03*
X1085300Y-90700D03*
X1070500Y-67900D03*
X1074400Y-39100D03*
X1079600Y-50700D03*
X1087700Y-37886D03*
X1045800Y-75936D03*
X1058333Y-72770D03*
X1061325Y-40378D03*
X1054625Y-40278D03*
X1079455Y-30742D03*
X1043000Y-67600D03*
X1043112Y-34912D03*
X1066600Y-72800D03*
X1066225Y-40278D03*
X1054593Y-51122D03*
X1078900Y-45782D03*
X1085800Y-57100D03*
X1070918Y-73618D03*
X1076000Y-10500D03*
X1043303Y-27685D03*
X1045873Y-24660D03*
X1043513Y-21696D03*
X1077505Y22405D03*
X1076418Y31082D03*
X1076944Y35182D03*
X1077260Y42612D03*
X1077400Y52000D03*
X1077082Y38982D03*
X1076905Y46195D03*
X1076299Y27282D03*
X1054800Y22405D03*
X1078500Y99000D03*
X1043703Y112543D03*
Y107543D03*
Y102543D03*
X1041003Y93543D03*
X1043703Y97543D03*
X1062854Y83434D03*
X1078500Y135500D03*
X1043500Y310500D03*
X1048500Y346000D03*
X1058500Y368500D03*
X1045000Y364000D03*
X1050100Y392600D03*
Y397600D03*
Y402600D03*
X1044600Y392500D03*
Y397500D03*
Y402500D03*
X1041500Y382858D03*
X1045292Y384688D03*
X1044600Y407500D03*
X1050100Y407600D03*
X1042833Y434409D03*
X1074425Y447225D03*
X1071950Y453288D03*
X1043674Y451921D03*
X1043500Y446600D03*
X1042800Y442000D03*
X1047000Y492000D03*
X1079000Y477000D03*
X1058000D03*
X1069018Y456900D03*
X1065985Y460500D03*
X1045106Y561249D03*
X1058000Y616000D03*
X1073000Y676000D03*
X1047000Y751000D03*
X1045163Y840400D03*
X1082000Y815500D03*
X1054419Y839493D03*
Y828081D03*
X1050763Y829163D03*
X1086600Y833200D03*
X1054000Y866000D03*
X1075500Y848000D03*
X1044680Y921400D03*
X1053200Y901703D03*
X1043882Y901568D03*
X1044101Y927130D03*
X1083633Y932172D03*
X1073408Y942399D03*
X1058571Y943852D03*
X1072000Y1035000D03*
X1053099Y1021657D03*
X1048512Y1021378D03*
X1041616Y997225D03*
X1052000Y1054000D03*
X1082500Y1067100D03*
X1073500D03*
X1054080Y1077680D03*
X1069000Y1067100D03*
X1064500Y1096150D03*
X1068700Y1096600D03*
X1087700Y1125800D03*
X1083355Y1125903D03*
X1070155D03*
X1048960Y1113900D03*
Y1117700D03*
X1041280Y1121500D03*
Y1113900D03*
Y1117700D03*
X1081078Y1095362D03*
X1083660Y1092700D03*
X1041280Y1095500D03*
Y1091700D03*
Y1100500D03*
X1048960Y1095500D03*
Y1091700D03*
Y1099300D03*
X1054080Y1113900D03*
Y1117700D03*
X1068700Y1108700D03*
X1083355Y1116103D03*
X1070155D03*
X1075600Y1179090D03*
X1053743Y1174221D03*
X1046900Y1168000D03*
X1052522Y1145153D03*
X1076032Y1191144D03*
X1070000Y1184100D03*
X1079500Y1276100D03*
X1047000Y1258687D03*
X1051300Y1253300D03*
X1077300Y1271700D03*
X1042343Y1324216D03*
X1048251Y1349992D03*
X1046372Y1356326D03*
X1042343Y1337616D03*
X1042443Y1342668D03*
X1042343Y1330916D03*
X1076754Y1455075D03*
X1072754D03*
X1044654D03*
X1048654D03*
X1134500Y-103500D03*
X1117535Y-115157D03*
X1115000Y-77500D03*
X1097600Y-82462D03*
X1107700Y-76800D03*
X1100929Y-90371D03*
X1116600Y-85538D03*
X1106300Y-94800D03*
X1089318Y-91682D03*
X1114400Y-55662D03*
X1093900Y-64500D03*
X1113300Y-44100D03*
X1101246Y-31005D03*
X1124024Y-30840D03*
X1128765Y-34297D03*
X1094200Y-38400D03*
X1111254Y-31020D03*
X1105328Y-31005D03*
X1094300Y-60300D03*
X1103300Y-60000D03*
X1115603Y-60293D03*
X1134110Y176500D03*
X1136203Y167600D03*
X1089300Y836100D03*
X1119159Y878130D03*
Y873130D03*
Y868130D03*
X1116159Y870630D03*
Y875630D03*
X1100847Y905617D03*
X1105847D03*
X1110847D03*
X1108347Y902617D03*
X1103347D03*
X1119700Y1067200D03*
X1124500D03*
X1091400Y1070900D03*
X1091494Y1075994D03*
X1097800Y1070700D03*
X1097500Y1075100D03*
X1103800Y1070600D03*
Y1075600D03*
X1128900Y1067200D03*
X1101580Y1091120D03*
X1107100Y1096050D03*
X1111600Y1097800D03*
X1124100Y1125100D03*
X1119500D03*
X1115000D03*
X1123600Y1096400D03*
X1123838Y1092800D03*
X1123600Y1100000D03*
X1133981Y1096283D03*
X1134002Y1092600D03*
X1134103Y1099881D03*
X1137436Y1124750D03*
X1128800Y1125100D03*
X1092200Y1125800D03*
X1103064Y1113626D03*
X1099020Y1112276D03*
X1096460Y1115125D03*
X1092742Y1113462D03*
X1134100Y1433300D03*
X1090818Y1531620D03*
X1092927Y1558887D03*
Y1555087D03*
X1095938Y1531620D03*
Y1535420D03*
X1090818D03*
X1096547Y1558887D03*
Y1555087D03*
X1139500Y-58500D03*
X1150000Y-63000D03*
X1146768Y-31238D03*
X1139808Y-31171D03*
X1149699Y-35153D03*
X1142293Y-37522D03*
X1181568Y55168D03*
X1181868Y50568D03*
Y45568D03*
X1181568Y60168D03*
X1178268Y64068D03*
X1183268D03*
X1184088Y101360D03*
X1184141Y96794D03*
X1178268Y85068D03*
Y69068D03*
Y89068D03*
X1183268Y85068D03*
Y69068D03*
Y89068D03*
X1178656Y104637D03*
X1176952Y93390D03*
X1177500Y153500D03*
X1140550Y179200D03*
X1142800Y174637D03*
X1140500Y171400D03*
X1182590Y254388D03*
X1171749Y259163D03*
X1175400Y258800D03*
X1174037Y281343D03*
X1176300Y284500D03*
X1180953Y284800D03*
X1185588Y285035D03*
X1185000Y281343D03*
X1176100Y270603D03*
X1176300Y288600D03*
X1173500Y397000D03*
X1156500Y467000D03*
X1166500Y635000D03*
X1156500Y619000D03*
X1176835Y618934D03*
X1156500Y650000D03*
X1175568Y712300D03*
X1171968D03*
X1175568Y715900D03*
X1171968D03*
X1173368Y730300D03*
X1171968Y719500D03*
X1175568D03*
X1173368Y726700D03*
Y723100D03*
X1181000Y814000D03*
X1156500Y813000D03*
X1179000Y829500D03*
X1166500D03*
X1138198Y832424D03*
X1158500Y868500D03*
X1172736Y1031786D03*
X1177036Y1032086D03*
X1144580Y1078680D03*
X1170140Y1043939D03*
X1172564Y1118373D03*
X1152880Y1097672D03*
X1152682Y1091138D03*
X1149984Y1115804D03*
X1143550Y1120317D03*
X1139524Y1121817D03*
X1152800Y1223062D03*
X1152700Y1216213D03*
X1150420Y1229800D03*
X1181400Y1266100D03*
X1184000Y1260100D03*
X1149823Y1233373D03*
X1144000Y1310000D03*
X1150232Y1316358D03*
X1154500Y1327500D03*
X1150911Y1329500D03*
X1147900Y1421500D03*
X1143900Y1431000D03*
X1142400Y1427700D03*
X1146002Y1427906D03*
X1145007Y1424446D03*
X1148556Y1425056D03*
X1153000Y1496000D03*
X1163000Y1612000D03*
X1141000Y1632000D03*
X1228500Y12500D03*
X1204768Y64368D03*
X1199768D03*
X1209768D03*
X1204068Y50368D03*
Y45368D03*
X1203768Y60568D03*
Y55568D03*
X1188268Y64068D03*
X1224000Y104000D03*
X1199768Y69368D03*
X1204768D03*
X1209768D03*
X1204768Y85368D03*
X1199768D03*
X1209768D03*
Y89368D03*
X1199768D03*
X1204768D03*
X1188268Y85068D03*
Y69068D03*
Y89068D03*
X1215795Y181242D03*
X1186500Y220500D03*
X1224800Y225200D03*
X1219917Y239646D03*
X1215600Y261800D03*
X1219962Y244739D03*
X1186600Y253200D03*
X1215547Y246355D03*
X1194700Y261700D03*
X1189700Y308527D03*
X1190200Y285023D03*
X1201835Y305319D03*
X1193800Y307857D03*
X1198100Y306858D03*
X1194600Y288237D03*
X1197000Y279400D03*
X1226045Y431102D03*
X1232500Y541000D03*
X1197868Y730300D03*
X1194268D03*
Y723100D03*
Y726700D03*
X1197868Y723100D03*
Y726700D03*
X1192068Y712300D03*
X1195668D03*
X1192068Y715900D03*
X1195668D03*
Y719500D03*
X1192068D03*
X1188000Y753000D03*
X1192000Y869000D03*
X1232700Y950400D03*
X1194000Y1037900D03*
X1229691Y1148580D03*
X1232842Y1140722D03*
X1198130Y1151410D03*
X1205303Y1227604D03*
X1214500Y1320500D03*
X1220500Y1311000D03*
X1194000Y1499000D03*
X1240500Y20000D03*
X1254000Y105000D03*
X1281500Y103500D03*
X1278421Y205974D03*
X1281603Y203340D03*
X1282106Y180492D03*
X1280800Y167200D03*
X1282287Y243489D03*
X1277606Y217441D03*
X1282106Y235492D03*
X1248193Y242618D03*
X1255600Y237300D03*
X1250016Y247017D03*
X1253300Y227700D03*
X1273200Y263700D03*
X1276200Y277400D03*
X1262075Y297100D03*
X1250500Y266600D03*
X1280000Y430000D03*
X1235796Y517450D03*
X1250011Y516707D03*
X1239362Y524168D03*
X1253511Y517606D03*
X1264878Y508068D03*
X1282106Y648248D03*
Y633248D03*
Y618248D03*
X1253800Y689600D03*
X1277606Y670197D03*
X1282106Y688248D03*
X1277606Y660748D03*
Y651299D03*
X1282106Y728248D03*
Y718248D03*
Y698248D03*
X1268400Y716100D03*
X1265891Y699583D03*
X1263250Y823436D03*
X1243200Y933700D03*
X1259808Y927260D03*
X1250475Y969248D03*
X1271296Y986867D03*
X1274413Y984613D03*
X1279599Y976407D03*
X1253338Y980784D03*
X1253975Y970147D03*
X1264269Y981248D03*
X1263618Y990606D03*
X1268378Y990608D03*
X1239900Y1024000D03*
X1256142Y1029316D03*
X1279081Y1071085D03*
X1252400Y1054100D03*
X1277606Y1122953D03*
Y1113504D03*
Y1104055D03*
X1282106Y1101004D03*
Y1086004D03*
X1251250Y1141700D03*
X1282106Y1171004D03*
Y1151004D03*
Y1141004D03*
X1246557Y1148155D03*
X1249600Y1155800D03*
X1272755Y1137293D03*
X1260300Y1169000D03*
X1240314Y1139741D03*
X1268948Y1150173D03*
X1282106Y1181004D03*
X1254800Y1269600D03*
X1257000Y1300000D03*
X1263500Y1318500D03*
X1240276Y1356700D03*
X1319000Y12000D03*
X1309000Y45500D03*
X1318500Y34500D03*
X1323829Y55929D03*
X1328295Y55800D03*
X1320055Y68000D03*
X1319100Y78800D03*
X1323521Y79179D03*
X1312999Y107280D03*
X1317661Y107896D03*
X1299569Y84272D03*
X1304563Y84309D03*
Y100771D03*
X1299569Y100639D03*
X1312263Y95463D03*
X1327921Y78900D03*
X1308228Y93399D03*
X1315961Y98112D03*
X1289000Y145400D03*
X1314794Y162944D03*
X1324134Y126967D03*
X1313127Y120839D03*
X1315118Y126967D03*
X1324207Y138756D03*
X1315102Y137903D03*
X1302074Y183779D03*
X1311200Y172661D03*
X1304293Y165909D03*
X1315838Y188804D03*
X1297507Y195492D03*
X1298700Y272800D03*
X1298500Y302900D03*
X1305000Y299400D03*
X1313000Y302900D03*
X1313915Y263541D03*
X1289000Y309500D03*
X1311000Y321000D03*
X1303500Y434000D03*
X1287000Y456000D03*
X1310000Y597000D03*
X1289106Y594626D03*
X1303800Y636417D03*
X1311200Y625417D03*
X1307500Y615417D03*
X1315400Y648017D03*
X1312000Y615417D03*
X1302500Y718917D03*
X1314000Y717417D03*
X1298500Y752417D03*
X1305000D03*
X1313000D03*
X1289106Y766870D03*
X1316000Y772200D03*
X1310500Y774700D03*
X1312767Y885535D03*
X1286000Y982200D03*
X1284695Y956586D03*
X1305000Y1041500D03*
X1289114Y1048624D03*
X1311200Y1078173D03*
X1305100Y1068173D03*
X1317400Y1068000D03*
X1309600Y1068173D03*
X1303800Y1089173D03*
X1315300Y1100773D03*
X1302500Y1171673D03*
X1313950Y1165990D03*
X1300065Y1206008D03*
X1305000Y1205173D03*
X1313000D03*
X1289106Y1219626D03*
X1357500Y43500D03*
X1347500Y21000D03*
X1332500Y56500D03*
X1351200Y68600D03*
X1359350Y66350D03*
X1351201Y90099D03*
X1358355Y81488D03*
X1338215Y107586D03*
X1336034Y82542D03*
X1334383Y75892D03*
X1340961Y78811D03*
X1343521Y85472D03*
X1347607Y101337D03*
X1346081Y80671D03*
X1348641Y83326D03*
X1352351Y101724D03*
X1350779Y106496D03*
X1348641Y110550D03*
X1333281Y85133D03*
X1341922Y105649D03*
X1354500Y75400D03*
X1332934Y137712D03*
X1349931Y138361D03*
X1338400Y126015D03*
X1333988Y161471D03*
X1358971Y129978D03*
X1362685Y130109D03*
X1351665Y128325D03*
X1343112Y128997D03*
X1364017Y123277D03*
X1337662Y137188D03*
X1334500Y202548D03*
Y207548D03*
Y212548D03*
X1377463Y237100D03*
X1334500Y217548D03*
X1372274Y272874D03*
X1355991Y275272D03*
X1374338Y292900D03*
X1358573Y290900D03*
X1372000Y335000D03*
X1375700Y413400D03*
X1338000Y546500D03*
X1346363Y516578D03*
X1332148Y517321D03*
X1357316Y542311D03*
X1346057Y529857D03*
X1338100Y520300D03*
X1353500Y518900D03*
X1359882Y508014D03*
X1364882D03*
X1337500Y576500D03*
X1355700Y587600D03*
X1359700D03*
X1372272Y573560D03*
X1336000Y627000D03*
X1375463Y689917D03*
X1334000Y666417D03*
Y661917D03*
Y657417D03*
Y652917D03*
X1373553Y700994D03*
X1347600Y734078D03*
X1344062Y737800D03*
X1339500Y794000D03*
X1354500Y747304D03*
X1360920Y749829D03*
X1334300Y771200D03*
X1338729Y776131D03*
X1338700Y771500D03*
X1334329Y775831D03*
X1373519Y761900D03*
X1341219Y933282D03*
X1346080Y907004D03*
X1344000Y987500D03*
X1362000Y987000D03*
X1331070Y966090D03*
X1348796Y969488D03*
X1378100Y972100D03*
X1339404Y969600D03*
X1353762Y969886D03*
X1367382Y961355D03*
X1362382D03*
X1349829Y1014840D03*
X1365551Y1028250D03*
X1368935Y1123365D03*
X1361074Y1114565D03*
X1334500Y1104700D03*
Y1111173D03*
Y1116173D03*
Y1121173D03*
X1365461Y1136100D03*
X1375463Y1142673D03*
X1364713Y1143791D03*
X1360238Y1143867D03*
X1370716Y1148037D03*
X1351321Y1152553D03*
X1355733Y1241900D03*
X1369600Y1330100D03*
X1373700Y1330000D03*
X1365551Y1353500D03*
X1413268Y146062D03*
X1401819Y207992D03*
X1394705Y195413D03*
X1406319Y180492D03*
X1405100Y166000D03*
X1427663Y167032D03*
X1403963Y245492D03*
X1385051Y218684D03*
X1406000Y236700D03*
X1384475Y255839D03*
X1426713Y266161D03*
X1426400Y307400D03*
X1406319Y275492D03*
Y265492D03*
X1398493Y314114D03*
X1384713Y323200D03*
X1400000Y406000D03*
X1427000Y380000D03*
X1414882Y397271D03*
X1395300Y438500D03*
X1418225Y421700D03*
X1425000Y480000D03*
X1405000D03*
Y460000D03*
X1385000Y480000D03*
X1396500Y511000D03*
X1383500Y509500D03*
X1418493Y531407D03*
X1425600Y544600D03*
X1418507Y517007D03*
X1407936Y552099D03*
Y548099D03*
X1425200Y540100D03*
X1414319Y523900D03*
X1413319Y594626D03*
X1413400Y575000D03*
X1396297Y573397D03*
X1421239Y558029D03*
X1396297Y579803D03*
X1421239Y562229D03*
X1406319Y648248D03*
Y633248D03*
Y618248D03*
X1421500Y664000D03*
X1401819Y670197D03*
X1406319Y688248D03*
X1401819Y660748D03*
Y651299D03*
X1426713Y718917D03*
X1406319Y728248D03*
Y718248D03*
Y698248D03*
X1383952Y717435D03*
X1422713Y752417D03*
X1398245Y766870D03*
X1395000Y791500D03*
X1392355Y886696D03*
X1391000Y932400D03*
X1380300Y930200D03*
X1390000Y955500D03*
X1384800Y1002666D03*
X1390500Y1048000D03*
X1406319Y1071004D03*
X1413319Y1047382D03*
X1406319Y1086004D03*
Y1101004D03*
X1401819Y1104055D03*
X1385494Y1113504D03*
X1401819Y1122953D03*
X1406319Y1141004D03*
Y1151004D03*
Y1171004D03*
X1426713Y1171673D03*
X1383899Y1166690D03*
X1406319Y1181004D03*
X1413319Y1219626D03*
X1422713Y1205173D03*
X1388500Y1224900D03*
X1413000Y1241500D03*
X1387000Y1243500D03*
X1386500Y1258000D03*
X1418000Y1291500D03*
X1400000Y1320000D03*
X1420000D03*
X1381800Y1329600D03*
X1431713Y162661D03*
X1463804Y138605D03*
X1436204Y159247D03*
X1428013Y185956D03*
X1445994Y174086D03*
X1440300Y188000D03*
X1456373Y168971D03*
X1458764Y212625D03*
Y208025D03*
Y203425D03*
X1438186Y261287D03*
X1458764Y217225D03*
X1463000Y307000D03*
X1439300Y301500D03*
X1429800Y302500D03*
X1447170Y337890D03*
X1466500Y338100D03*
X1444238Y349852D03*
X1439654D03*
X1441770Y365790D03*
X1461100Y366000D03*
X1441970Y403990D03*
X1461300Y404200D03*
X1431909Y359311D03*
X1439500Y421500D03*
X1440000Y460000D03*
X1449576Y495482D03*
X1468605Y493549D03*
X1463000Y490638D03*
X1457200Y549600D03*
X1470700Y522100D03*
X1456439Y515000D03*
X1448261D03*
X1435200D03*
X1443700D03*
X1460200D03*
X1452200D03*
X1465700D03*
X1439200D03*
X1442500Y548400D03*
X1456450Y529600D03*
X1448450D03*
X1452279Y563600D03*
X1464700Y585600D03*
X1470000Y580000D03*
X1460274Y592498D03*
X1459200Y579600D03*
X1452200D03*
X1442500Y554700D03*
X1455750Y572350D03*
X1474700Y569100D03*
X1447700Y579600D03*
X1474700Y579100D03*
X1428013Y636417D03*
X1435413Y625417D03*
X1431713Y615417D03*
X1439713Y647917D03*
X1455202Y618557D03*
X1436213Y615417D03*
X1458713Y658417D03*
Y663417D03*
Y668417D03*
Y652217D03*
X1449000Y698000D03*
X1438087Y713756D03*
X1429213Y752417D03*
X1437213D03*
X1474083Y764750D03*
X1471608Y768500D03*
X1432000Y831000D03*
X1459500Y814000D03*
X1450500Y802500D03*
X1459500Y796500D03*
X1473000Y798000D03*
X1433500Y864500D03*
X1435300Y882700D03*
X1440500Y893500D03*
X1448000Y910000D03*
X1457500Y987500D03*
X1440000Y986500D03*
X1473008Y969646D03*
X1458967Y969535D03*
X1463616Y969265D03*
X1451800Y1004700D03*
X1433500Y1044000D03*
X1456000D03*
X1435413Y1078173D03*
X1431713Y1068173D03*
X1446213Y1062300D03*
X1436213Y1068173D03*
X1428013Y1089173D03*
X1439713Y1100773D03*
X1461713Y1123173D03*
Y1118173D03*
Y1113173D03*
X1461700Y1107200D03*
X1438213Y1170173D03*
X1470953Y1152427D03*
X1475953D03*
X1429213Y1205173D03*
X1437213D03*
X1467000Y1221800D03*
X1458000Y1265500D03*
X1473600Y1242777D03*
X1460000Y1300000D03*
Y1320000D03*
X1440000D03*
X1511177Y125412D03*
X1498900Y235800D03*
X1499775Y248061D03*
X1508925Y323200D03*
X1505000Y378500D03*
X1520000Y421500D03*
X1481938Y489926D03*
X1479212Y535612D03*
X1494100Y526400D03*
X1507900Y539100D03*
X1481938Y512568D03*
X1485932Y522335D03*
X1500600Y523300D03*
X1502400Y544100D03*
X1497849Y545264D03*
X1486594Y508098D03*
X1491594D03*
X1513200Y519700D03*
X1509800Y516100D03*
X1509911Y553511D03*
X1478700Y579100D03*
X1502400Y554100D03*
X1494400Y560400D03*
Y556100D03*
X1494462Y692179D03*
X1500539Y739639D03*
X1498000Y743000D03*
X1505900Y717600D03*
X1495480Y704558D03*
X1489000Y723000D03*
X1515000Y789000D03*
X1520000Y776000D03*
X1499500Y774000D03*
X1476558Y759088D03*
X1479033Y762259D03*
X1486600Y786559D03*
X1499500Y831000D03*
X1510500Y878000D03*
X1510000Y860500D03*
X1505900Y930400D03*
X1521200Y928000D03*
X1512500Y949000D03*
X1503394Y968179D03*
X1477974Y970044D03*
X1491594Y961355D03*
X1486594D03*
X1508500Y1028500D03*
X1484000Y992315D03*
X1481500Y995758D03*
X1478194Y1017166D03*
X1481529Y1030500D03*
X1508500Y1050500D03*
X1488500Y1096000D03*
X1489096Y1131456D03*
X1489108Y1121674D03*
X1485608Y1113628D03*
X1499675Y1142673D03*
X1489333Y1147664D03*
X1504200Y1171300D03*
X1485833Y1140369D03*
X1495900Y1149000D03*
X1480000Y1320000D03*
X1491662Y1351300D03*
X1494662Y1336000D03*
X1497200Y1342500D03*
X1501600Y1342300D03*
X1525336Y149369D03*
X1555925Y162661D03*
X1545383Y164116D03*
X1560000Y140000D03*
X1560425Y162661D03*
X1552225Y183661D03*
X1559625Y172661D03*
X1563925Y195261D03*
X1526031Y207992D03*
Y198543D03*
X1530531Y195492D03*
Y180492D03*
Y245492D03*
X1526031Y217441D03*
X1530142Y238021D03*
X1550925Y266161D03*
X1546925Y299661D03*
X1553425D03*
X1561425D03*
X1562425Y264661D03*
X1530531Y275492D03*
Y265492D03*
X1537531Y314114D03*
X1545000Y455000D03*
X1560000D03*
X1525000D03*
X1568500Y438500D03*
X1545000Y475000D03*
X1560000D03*
Y500000D03*
Y525000D03*
X1568500Y544100D03*
X1568000Y548500D03*
X1552000Y584500D03*
X1566000Y595000D03*
X1537531Y594626D03*
X1552225Y636417D03*
X1559625Y625417D03*
X1555925Y615417D03*
X1530531Y648248D03*
Y633248D03*
Y618248D03*
X1560425Y615417D03*
X1558925Y650017D03*
X1526031Y670197D03*
X1530531Y688248D03*
X1526031Y660748D03*
Y651299D03*
X1565593Y654856D03*
X1565618Y660773D03*
Y665773D03*
Y670773D03*
X1550925Y718917D03*
X1562425Y717417D03*
X1530531Y728248D03*
Y718248D03*
Y698248D03*
X1526000Y728000D03*
X1555000Y770000D03*
X1546925Y752417D03*
X1553425D03*
X1561425D03*
X1537531Y766870D03*
X1525000Y878000D03*
X1570500Y888400D03*
X1564500Y931000D03*
X1548500Y933000D03*
X1564000Y949000D03*
X1552500Y1028000D03*
X1557500Y1043500D03*
X1537531Y1047382D03*
X1559625Y1078173D03*
X1555925Y1068173D03*
X1530531Y1071004D03*
X1570425Y1062000D03*
X1560425Y1068173D03*
X1552225Y1089173D03*
X1526031Y1122953D03*
Y1113504D03*
Y1104055D03*
X1530531Y1101004D03*
Y1086004D03*
X1547800Y1098819D03*
X1552800D03*
X1557800D03*
X1562800D03*
X1550925Y1171673D03*
X1552575Y1139700D03*
X1562425Y1170173D03*
X1530531Y1171004D03*
Y1151004D03*
X1528723Y1138918D03*
X1546898Y1204827D03*
X1553425Y1208897D03*
X1561425Y1205173D03*
X1537879Y1219626D03*
X1530531Y1181004D03*
X1558650Y1217426D03*
X1600000Y20000D03*
X1620000D03*
X1580000D03*
X1600000Y60000D03*
X1620000Y40000D03*
X1600000D03*
X1580000D03*
Y60000D03*
X1620000Y100000D03*
X1600000Y80000D03*
X1620000D03*
X1580000D03*
X1620000Y140000D03*
Y120000D03*
X1585757Y134147D03*
X1607000Y199000D03*
X1579371Y166019D03*
X1582925Y210661D03*
Y205661D03*
Y200661D03*
X1595500Y258500D03*
X1621100Y240561D03*
X1608000Y256000D03*
X1621100Y244661D03*
X1582925Y215661D03*
X1600000Y340000D03*
X1620000D03*
Y320000D03*
X1600000D03*
X1579500Y331000D03*
X1597245Y516662D03*
X1583030Y517405D03*
X1586596Y518723D03*
X1600745Y517561D03*
X1615807Y508600D03*
X1610807D03*
X1573000Y565500D03*
X1578926Y618657D03*
X1620469Y697517D03*
X1580000Y780000D03*
X1576500Y928500D03*
X1584800Y895800D03*
X1587400Y912200D03*
X1608200Y914400D03*
X1618200Y916800D03*
X1597221Y969572D03*
X1583180Y969461D03*
X1574576Y976700D03*
X1615494Y973179D03*
X1587829Y969191D03*
X1602187Y969970D03*
X1615807Y961355D03*
X1610807D03*
X1596000Y990000D03*
X1580381Y1007066D03*
X1602400Y1019366D03*
X1620059Y1032932D03*
X1611500Y1078000D03*
X1593000Y1043500D03*
X1620059Y1128071D03*
X1615909Y1150262D03*
X1593500Y1185500D03*
X1581500Y1240000D03*
X1613400Y1236500D03*
X1600000Y1320000D03*
X1640000Y20000D03*
X1660000D03*
X1640000Y60000D03*
X1660000D03*
Y40000D03*
X1640000D03*
Y100000D03*
X1660000D03*
X1640000Y80000D03*
X1660000D03*
Y120000D03*
X1640000D03*
X1661744Y141870D03*
X1650244Y207992D03*
Y198543D03*
X1654744Y195492D03*
Y180492D03*
Y165492D03*
Y245492D03*
X1650244Y217441D03*
X1654744Y235492D03*
X1652387Y277343D03*
X1653789Y267766D03*
X1622738Y264938D03*
X1639000Y320000D03*
X1640000Y340000D03*
X1660000D03*
X1661744Y314114D03*
X1660000Y400000D03*
X1640000Y360000D03*
X1660000Y440000D03*
Y480000D03*
X1640000D03*
Y460000D03*
X1660000D03*
X1640000Y500000D03*
X1660000D03*
Y520000D03*
X1640000D03*
X1660000Y540000D03*
X1640000D03*
Y560000D03*
X1660000D03*
X1661744Y594626D03*
X1654744Y648248D03*
Y633248D03*
Y618248D03*
X1623888Y689917D03*
X1652962Y670204D03*
X1654744Y688248D03*
X1650244Y660748D03*
Y651299D03*
X1637000Y729000D03*
X1638000Y740000D03*
X1654744Y728248D03*
Y718248D03*
Y698248D03*
X1621138Y719238D03*
X1630000Y780000D03*
Y760000D03*
X1661744Y766870D03*
X1625000Y800000D03*
X1643344Y887455D03*
X1646013Y884255D03*
X1639644Y889755D03*
X1651500Y913500D03*
X1633600Y936300D03*
X1621787Y917108D03*
X1636400Y925800D03*
X1650000Y950000D03*
Y980000D03*
X1629094Y975179D03*
X1653500Y1016500D03*
X1650000Y1000000D03*
X1632000Y1049500D03*
X1654744Y1071004D03*
X1661744Y1047382D03*
X1650244Y1122953D03*
Y1113504D03*
Y1104055D03*
X1654744Y1101004D03*
Y1086004D03*
X1627563Y1132075D03*
X1627802Y1118949D03*
X1627769Y1110037D03*
X1624198Y1111309D03*
X1635688Y1141158D03*
X1650841Y1168660D03*
X1654744Y1151004D03*
Y1141004D03*
X1627197Y1143044D03*
X1633138Y1165673D03*
X1635688Y1153773D03*
X1661744Y1219626D03*
X1668378Y1181004D03*
X1640000Y1260000D03*
X1660000D03*
X1640000Y1320000D03*
Y1300000D03*
X1660000Y1320000D03*
Y1300000D03*
Y1280000D03*
X1640000D03*
X1624500Y1349100D03*
X1700000Y20000D03*
X1680000D03*
X1700000Y60000D03*
Y40000D03*
X1680000Y60000D03*
Y40000D03*
Y100000D03*
Y80000D03*
X1700000Y100000D03*
Y80000D03*
Y140000D03*
Y120000D03*
X1680000D03*
X1679500Y144000D03*
X1680138Y162661D03*
X1684638D03*
X1676438Y183661D03*
X1683838Y172661D03*
X1688138Y195261D03*
X1703584Y166019D03*
X1707138Y210661D03*
Y205661D03*
Y200661D03*
Y215661D03*
X1675475Y267424D03*
X1671138Y299661D03*
X1677638D03*
X1685638D03*
X1686638Y264661D03*
X1678500Y320000D03*
X1700000Y400000D03*
X1680000Y380000D03*
X1700000Y360000D03*
X1680000Y440000D03*
Y420000D03*
X1700000Y440000D03*
Y420000D03*
Y460000D03*
X1680000Y480000D03*
Y460000D03*
Y500000D03*
Y520000D03*
X1700000Y540000D03*
X1680000D03*
X1707495Y517152D03*
X1711061Y518470D03*
X1700000Y560000D03*
X1680000D03*
X1676438Y636417D03*
X1683838Y625417D03*
X1680138Y615417D03*
X1688138Y648017D03*
X1705000Y618667D03*
X1684638Y615417D03*
X1707100Y652500D03*
X1707138Y658417D03*
Y663417D03*
Y668417D03*
X1675138Y718917D03*
X1686638Y717417D03*
X1710000Y770000D03*
Y785000D03*
X1685000Y770000D03*
X1671138Y752417D03*
X1677638D03*
X1685638D03*
X1709000Y915000D03*
X1687000Y905500D03*
X1692100Y923600D03*
X1704010Y898000D03*
X1716500Y943500D03*
X1674814Y961977D03*
X1677056Y954636D03*
X1680012Y952402D03*
X1706000Y1022000D03*
X1717681Y1006054D03*
X1712181Y1001554D03*
X1685047Y1014966D03*
X1680087Y1023983D03*
X1671422Y1009266D03*
X1690279Y1011526D03*
X1691771Y1035163D03*
X1683838Y1078173D03*
X1680138Y1068173D03*
X1685100Y1054000D03*
X1679300Y1043169D03*
X1694638Y1063600D03*
X1684638Y1068173D03*
X1688138Y1100773D03*
X1676438Y1089173D03*
X1707138Y1111173D03*
Y1116173D03*
Y1121173D03*
X1707200Y1105200D03*
X1686638Y1170173D03*
X1675138Y1171673D03*
X1685638Y1205173D03*
X1677638D03*
X1671138D03*
X1702838Y1215300D03*
X1680000Y1240000D03*
X1700000Y1260000D03*
X1680000D03*
X1710617Y1231429D03*
X1715049Y1234000D03*
X1700000Y1320000D03*
Y1300000D03*
Y1280000D03*
X1680000Y1320000D03*
Y1300000D03*
Y1280000D03*
X1760000Y20000D03*
X1740000D03*
X1720000D03*
X1760000Y60000D03*
Y40000D03*
X1740000D03*
Y60000D03*
X1720000Y40000D03*
Y60000D03*
X1740000Y100000D03*
X1760000D03*
X1740000Y80000D03*
X1760000D03*
X1720000Y100000D03*
Y80000D03*
X1740000Y140000D03*
X1760000Y120000D03*
X1740000D03*
X1720000Y140000D03*
Y120000D03*
X1728500Y249500D03*
X1746600Y240561D03*
X1760486Y217441D03*
X1746400Y244561D03*
X1763500Y288000D03*
X1720000Y300000D03*
Y280000D03*
X1747550Y265000D03*
X1720000Y340000D03*
X1760000D03*
X1740000Y320000D03*
X1760000Y440000D03*
Y420000D03*
Y500000D03*
Y480000D03*
Y460000D03*
X1740000Y540000D03*
X1760000D03*
Y520000D03*
X1721710Y516409D03*
X1725100Y519300D03*
X1740019Y508600D03*
X1735019D03*
X1745000Y670000D03*
Y690000D03*
Y660000D03*
X1730000Y690000D03*
Y670000D03*
Y730000D03*
Y710000D03*
X1735000Y785000D03*
X1730000Y775000D03*
Y750000D03*
X1725000Y800000D03*
X1718000Y876000D03*
X1752000Y929200D03*
X1759884Y969161D03*
X1757600Y987200D03*
X1761600D03*
Y983200D03*
X1757600D03*
X1742001Y965464D03*
X1755010Y966285D03*
X1740019Y961355D03*
X1735019D03*
X1738863Y985225D03*
X1761600Y991200D03*
Y999200D03*
Y995200D03*
X1757600Y991200D03*
X1753600Y995200D03*
Y999200D03*
X1757600D03*
Y995200D03*
X1726681Y1001554D03*
X1719681D03*
X1722181Y1009054D03*
X1763714Y1015491D03*
X1755900Y1014600D03*
X1740499Y1008223D03*
X1749863Y1003925D03*
X1756100Y1004362D03*
X1746030Y1004209D03*
X1737241Y997843D03*
X1740363Y989225D03*
X1755000Y1045000D03*
X1725000D03*
X1745000Y1100000D03*
X1759055Y1113504D03*
X1736725Y1123446D03*
X1733245Y1115503D03*
X1748100Y1142673D03*
X1736871Y1158178D03*
X1736941Y1141871D03*
X1751400Y1173900D03*
X1732768Y1141697D03*
X1748100Y1153673D03*
X1718117Y1152553D03*
X1723117D03*
X1728000Y1204500D03*
X1755900Y1212704D03*
X1720000Y1320000D03*
X1760000D03*
X1753000Y1302000D03*
X1740000Y1346900D03*
X1780000Y60000D03*
Y40000D03*
X1800000Y100000D03*
Y80000D03*
X1780000Y100000D03*
Y80000D03*
X1800000Y120000D03*
X1780000D03*
X1785956Y141870D03*
X1804350Y162661D03*
X1808850D03*
X1801988Y183904D03*
X1808050Y172661D03*
X1812350Y195261D03*
X1774456Y207992D03*
Y198543D03*
X1778956Y195492D03*
Y180492D03*
X1775140Y165728D03*
X1778956Y245492D03*
Y235492D03*
X1799350Y266161D03*
X1795350Y299661D03*
X1801850D03*
X1809850D03*
X1810850Y264661D03*
X1778956Y275492D03*
Y265492D03*
X1785956Y314114D03*
X1800000Y440000D03*
X1780000D03*
X1800000Y500000D03*
X1780000D03*
X1800000Y480000D03*
Y460000D03*
X1780000Y480000D03*
Y460000D03*
X1800000Y540000D03*
X1780000D03*
X1800000Y520000D03*
X1780000D03*
X1800000Y560000D03*
X1785956Y594626D03*
X1800650Y636417D03*
X1808050Y625417D03*
X1804350Y615417D03*
X1812350Y648017D03*
X1778956Y648248D03*
Y633248D03*
Y618248D03*
X1808850Y615417D03*
X1774456Y670197D03*
X1778956Y688248D03*
X1774456Y660748D03*
Y651299D03*
X1799326Y717506D03*
X1811474Y717423D03*
X1778956Y728248D03*
Y718248D03*
Y698248D03*
X1766721Y716500D03*
Y720500D03*
X1795468Y752594D03*
X1801968D03*
X1809968D03*
X1785956Y766870D03*
X1773500Y879500D03*
X1813851Y927406D03*
X1771000Y944500D03*
X1799000Y945500D03*
X1788361Y964676D03*
X1799051Y963346D03*
X1768692Y966073D03*
X1797463Y968652D03*
X1806077Y961860D03*
X1782666Y961344D03*
X1777666D03*
X1783778Y970371D03*
X1788726Y1034726D03*
X1778863Y1005725D03*
X1787163Y1009741D03*
X1772863Y1005304D03*
X1778963Y999125D03*
X1772263Y995925D03*
X1785956Y1047382D03*
X1808050Y1078173D03*
X1800750Y1067973D03*
X1778956Y1071004D03*
X1812050Y1071223D03*
X1805250Y1067973D03*
X1800650Y1089173D03*
X1811968Y1100773D03*
X1774456Y1122953D03*
Y1104055D03*
X1778956Y1101004D03*
Y1086004D03*
X1799350Y1171673D03*
X1810850Y1170173D03*
X1778956Y1171004D03*
Y1151004D03*
Y1141004D03*
X1795350Y1205173D03*
X1801850D03*
X1809850D03*
X1785956Y1219626D03*
X1778956Y1181004D03*
X1772111Y1232695D03*
X1860000Y60000D03*
Y80000D03*
Y100000D03*
X1840000D03*
X1820000D03*
X1860000Y140000D03*
Y120000D03*
X1840000D03*
X1820000Y140000D03*
Y120000D03*
X1859017Y161725D03*
X1841021Y152968D03*
X1845517Y158475D03*
X1859117Y167375D03*
X1851717Y179075D03*
X1856219Y212661D03*
X1827796Y166019D03*
X1831350Y210661D03*
Y205661D03*
Y200661D03*
X1841169Y254661D03*
X1831350Y215661D03*
X1840000Y340000D03*
Y320000D03*
X1860000D03*
X1820000D03*
Y440000D03*
Y480000D03*
Y460000D03*
X1840000Y540000D03*
X1820000D03*
X1845545Y516536D03*
X1831330Y517279D03*
X1834896Y518597D03*
X1849045Y517435D03*
X1859232Y508600D03*
X1840000Y580000D03*
X1820000D03*
X1840000Y560000D03*
X1820000D03*
X1858917Y614481D03*
X1859117Y620131D03*
X1851717Y635331D03*
X1827667Y618703D03*
X1840855Y606200D03*
X1845417Y611231D03*
X1862200Y686700D03*
X1856219Y665417D03*
X1831350Y658417D03*
Y663417D03*
Y668417D03*
X1831300Y652600D03*
X1850000Y745000D03*
X1837576Y707417D03*
X1820000Y780000D03*
X1848491Y819787D03*
Y823787D03*
Y815787D03*
Y807787D03*
X1850151Y835119D03*
X1850177Y838746D03*
X1838239Y831626D03*
X1845579Y831731D03*
X1838311Y827911D03*
X1845651Y828016D03*
X1848491Y811787D03*
X1855676Y800787D03*
X1824170Y886349D03*
X1860276Y916059D03*
Y912059D03*
X1843731Y936066D03*
X1819541Y921500D03*
X1823937Y890883D03*
X1821152Y907899D03*
X1843811Y940067D03*
X1840419Y945557D03*
Y951057D03*
X1825945Y945449D03*
Y950949D03*
X1830665Y941751D03*
X1836165D03*
X1825971Y1015512D03*
Y1010012D03*
X1840445Y1015620D03*
Y1010120D03*
X1835895Y1020064D03*
X1830395D03*
X1857363Y1002625D03*
X1845363D03*
X1849363D03*
X1861363D03*
X1853363D03*
X1856437Y1106400D03*
X1836200Y1130000D03*
X1828850Y1106173D03*
Y1111173D03*
Y1116173D03*
Y1121173D03*
X1850532Y1153286D03*
X1836231Y1140669D03*
X1840585Y1151653D03*
X1836400Y1151900D03*
X1860000Y1320000D03*
X1842000Y1344700D03*
X1880000Y60000D03*
X1900000D03*
X1880000Y80000D03*
X1900000D03*
Y100000D03*
X1880000D03*
X1900000Y120000D03*
X1880000Y140000D03*
Y120000D03*
X1910169Y141870D03*
X1898669Y207992D03*
Y198543D03*
X1903169Y195492D03*
Y180492D03*
Y165492D03*
X1885204Y184345D03*
X1869500Y179134D03*
X1876938Y181062D03*
X1865669Y201661D03*
X1870669D03*
X1875669D03*
X1880669D03*
X1873500Y219000D03*
X1865169Y247161D03*
Y234661D03*
X1903169Y245492D03*
X1898669Y217441D03*
X1903169Y235492D03*
X1881088Y296184D03*
X1903169Y275492D03*
Y265492D03*
X1880969Y276861D03*
X1880000Y340000D03*
Y320000D03*
X1910169Y314114D03*
X1890000Y400000D03*
Y380000D03*
Y360000D03*
Y440000D03*
Y420000D03*
X1864232Y508600D03*
X1910169Y594626D03*
X1903169Y648248D03*
Y633248D03*
Y618248D03*
X1885300Y636800D03*
X1869500Y633500D03*
X1878900Y637000D03*
X1898669Y670197D03*
X1903169Y688248D03*
X1898669Y660748D03*
Y651299D03*
X1879669Y652917D03*
X1874669D03*
X1869669D03*
X1864669D03*
X1903169Y728248D03*
Y718248D03*
Y698248D03*
X1880969Y729617D03*
X1865169Y699917D03*
X1880000Y780000D03*
X1910169Y766870D03*
X1887169Y752917D03*
X1908107Y831894D03*
X1902607D03*
X1907999Y846368D03*
X1902499D03*
X1884800Y890750D03*
X1902441Y888500D03*
X1892443Y894350D03*
X1872276Y916059D03*
X1876276D03*
Y920059D03*
X1872276D03*
X1868276Y916059D03*
X1864276Y912059D03*
X1868276D03*
X1864276Y916059D03*
X1876276Y912059D03*
X1872276D03*
X1884200Y895000D03*
X1891676Y917759D03*
X1884500Y912500D03*
X1904000Y933500D03*
Y929000D03*
Y925000D03*
X1906500Y893400D03*
X1909358Y897500D03*
X1904000Y938000D03*
X1873001Y901396D03*
X1904000Y921000D03*
X1872190Y936766D03*
X1875801Y946796D03*
X1875769Y951122D03*
X1880122Y954062D03*
X1880383Y950341D03*
X1865363Y1002625D03*
X1867963Y996425D03*
X1868100Y1055410D03*
X1871000Y1073300D03*
X1903169Y1071004D03*
X1910169Y1047382D03*
X1884835Y1067400D03*
X1887402Y1050193D03*
X1872162Y1055426D03*
X1864617Y1040934D03*
X1888085Y1059938D03*
X1876662Y1055426D03*
X1863700Y1085000D03*
X1898669Y1122953D03*
Y1113504D03*
Y1104055D03*
X1903169Y1101004D03*
Y1086004D03*
X1864833Y1091419D03*
X1870779Y1091763D03*
X1875779D03*
X1880779D03*
X1863131Y1133108D03*
X1903169Y1171004D03*
X1903100Y1149700D03*
X1903169Y1141004D03*
X1864352Y1153308D03*
X1871174Y1138730D03*
X1887169Y1205673D03*
X1910169Y1219626D03*
X1903169Y1181004D03*
X1880969Y1182373D03*
X1900000Y1260000D03*
Y1280000D03*
Y1320000D03*
Y1300000D03*
X1873500Y1329000D03*
X1920000Y60000D03*
Y80000D03*
Y100000D03*
Y120000D03*
X1912551Y836444D03*
Y841944D03*
X1911676Y893469D03*
X1920000Y1260000D03*
Y1280000D03*
Y1320000D03*
Y1300000D03*
G54D27*
X429724Y63977D03*
X443898D03*
X458071D03*
X429724Y116339D03*
Y96654D03*
Y102166D03*
Y110827D03*
X443898Y116339D03*
X458071D03*
X436811Y114764D03*
X450984D03*
X443898Y96654D03*
X458071D03*
X443898Y102166D03*
X458071D03*
X436811Y100591D03*
X450984D03*
X436811Y106103D03*
X450984D03*
X443898Y110827D03*
X458071D03*
X436811Y120276D03*
X450984D03*
X472244Y63977D03*
X465157Y114764D03*
X472244Y116339D03*
X479331Y114764D03*
X465157Y100591D03*
Y106103D03*
X472244Y96654D03*
Y102166D03*
X479331Y100591D03*
Y106103D03*
X472244Y110827D03*
X465157Y120276D03*
X479331D03*
X514764Y63977D03*
X543110D03*
X528937D03*
X557283D03*
X514764Y106496D03*
Y92323D03*
X550197Y114764D03*
X536024D03*
X521850D03*
X543110Y116339D03*
X528937D03*
X521850Y110433D03*
X543110Y110827D03*
X528937D03*
X550197Y106103D03*
X536024D03*
X521850D03*
X550197Y100591D03*
X536024D03*
X521850D03*
X543110Y102166D03*
X528937D03*
X521850Y96260D03*
X543110Y96654D03*
X528937D03*
X557283Y116339D03*
Y110827D03*
Y102166D03*
Y96654D03*
X514764Y120670D03*
X550197Y120276D03*
X536024D03*
X564370Y114764D03*
Y106103D03*
Y100591D03*
Y120276D03*
X833859Y1594095D03*
Y1598425D03*
Y1603937D03*
Y1608268D03*
Y1612599D03*
X840945Y1598032D03*
X826772D03*
X840945Y1602363D03*
X826772D03*
X840945Y1607874D03*
X826772D03*
X840945Y1612205D03*
X826772D03*
X840945Y1616536D03*
X826772D03*
X833859Y1618111D03*
Y1622441D03*
Y1626772D03*
Y1632284D03*
Y1636614D03*
Y1640945D03*
Y1646457D03*
Y1650788D03*
X840945Y1622048D03*
X826772D03*
X840945Y1626378D03*
X826772D03*
X840945Y1630709D03*
X826772D03*
X840945Y1636221D03*
X826772D03*
X840945Y1640551D03*
X826772D03*
X840945Y1644882D03*
X826772D03*
X840945Y1650394D03*
X826772D03*
X876378Y1594095D03*
X862205D03*
X848032D03*
X876378Y1598425D03*
X862205D03*
X848032D03*
X876378Y1603937D03*
X862205D03*
X848032D03*
X876378Y1608268D03*
X862205D03*
X848032D03*
X876378Y1612599D03*
X862205D03*
X848032D03*
X890552Y1598032D03*
X869292D03*
X855118D03*
X890552Y1602363D03*
X869292D03*
X855118D03*
X890552Y1607874D03*
X869292D03*
X855118D03*
X890552Y1612205D03*
X869292D03*
X855118D03*
X890552Y1616536D03*
X869292D03*
X855118D03*
X876378Y1618111D03*
X862205D03*
X848032D03*
X876378Y1622441D03*
X862205D03*
X848032D03*
X876378Y1626772D03*
X862205D03*
X848032D03*
X876378Y1632284D03*
X862205D03*
X848032D03*
X876378Y1636614D03*
X862205D03*
X848032D03*
X876378Y1640945D03*
X862205D03*
X848032D03*
X876378Y1646457D03*
X862205D03*
X848032D03*
X876378Y1650788D03*
X862205D03*
X848032D03*
X890552Y1622048D03*
X869292D03*
X855118D03*
X890552Y1626378D03*
X869292D03*
X855118D03*
X890552Y1630709D03*
X869292D03*
X855118D03*
X890552Y1636221D03*
X869292D03*
X855118D03*
X890552Y1640551D03*
X869292D03*
X855118D03*
X890552Y1644882D03*
X869292D03*
X855118D03*
X890552Y1650394D03*
X869292D03*
X855118D03*
X911811Y1603937D03*
Y1608268D03*
Y1612599D03*
X904725Y1602363D03*
Y1607874D03*
Y1612205D03*
Y1616536D03*
X911811Y1594095D03*
Y1598425D03*
X904725Y1598032D03*
X897638Y1594095D03*
Y1598425D03*
Y1603937D03*
Y1608268D03*
Y1612599D03*
X911811Y1632284D03*
Y1636614D03*
Y1640945D03*
Y1646457D03*
Y1650788D03*
X904725Y1630709D03*
Y1636221D03*
Y1640551D03*
Y1644882D03*
Y1650394D03*
X911811Y1618111D03*
Y1622441D03*
Y1626772D03*
X904725Y1622048D03*
Y1626378D03*
X897638Y1618111D03*
Y1622441D03*
Y1626772D03*
Y1632284D03*
Y1636614D03*
Y1640945D03*
Y1646457D03*
Y1650788D03*
X1095420Y988592D03*
X1100932D03*
X1109593D03*
X1115105D03*
X1123766D03*
X1129278D03*
X1099357Y995678D03*
X1104869D03*
X1113530D03*
X1119042D03*
X1127703D03*
X1133215D03*
X1095420Y1002765D03*
X1100932D03*
X1109593D03*
X1115105D03*
X1123766D03*
X1129278D03*
X1099357Y1009852D03*
X1104869D03*
X1113530D03*
X1119042D03*
X1127703D03*
X1133215D03*
X1095420Y1016938D03*
X1100932D03*
X1109593D03*
X1115105D03*
X1123766D03*
X1129278D03*
X1099357Y1024025D03*
X1104869D03*
X1113530D03*
X1119042D03*
X1127703D03*
X1133215D03*
X1095420Y1031111D03*
X1100932D03*
X1109593D03*
X1115105D03*
X1123766D03*
X1129278D03*
X1099357Y1038198D03*
X1104869D03*
X1113530D03*
X1119042D03*
X1127703D03*
X1133215D03*
X1095420Y1160257D03*
Y1174430D03*
X1100932Y1160257D03*
Y1174430D03*
X1109593Y1160257D03*
Y1174430D03*
X1115105Y1160257D03*
Y1174430D03*
X1123766Y1160257D03*
Y1174430D03*
X1129278Y1160257D03*
Y1174430D03*
X1099357Y1167343D03*
X1104869D03*
X1113530D03*
X1119042D03*
X1127703D03*
X1133215D03*
X1095420Y1188603D03*
Y1202776D03*
Y1216949D03*
X1100932Y1188603D03*
Y1202776D03*
Y1216949D03*
X1109593Y1188603D03*
Y1202776D03*
Y1216949D03*
X1115105Y1188603D03*
Y1202776D03*
Y1216949D03*
X1123766Y1188603D03*
Y1202776D03*
Y1216949D03*
X1129278Y1188603D03*
Y1202776D03*
Y1216949D03*
X1099357Y1181516D03*
Y1195690D03*
Y1209863D03*
Y1224036D03*
X1104869Y1181516D03*
Y1195690D03*
Y1209863D03*
Y1224036D03*
X1113530Y1181516D03*
Y1195690D03*
Y1209863D03*
Y1224036D03*
X1119042Y1181516D03*
Y1195690D03*
Y1209863D03*
Y1224036D03*
X1127703Y1181516D03*
Y1195690D03*
Y1209863D03*
Y1224036D03*
X1133215Y1181516D03*
Y1195690D03*
Y1209863D03*
Y1224036D03*
X1095420Y1231123D03*
Y1245296D03*
Y1259469D03*
Y1273642D03*
X1100932Y1231123D03*
Y1245296D03*
Y1259469D03*
Y1273642D03*
X1109593Y1231123D03*
Y1245296D03*
Y1259469D03*
Y1273642D03*
X1115105Y1231123D03*
Y1245296D03*
Y1259469D03*
Y1273642D03*
X1123766Y1231123D03*
Y1245296D03*
Y1259469D03*
Y1273642D03*
X1129278Y1231123D03*
Y1245296D03*
Y1259469D03*
Y1273642D03*
X1099357Y1238209D03*
Y1252382D03*
Y1266556D03*
X1104869Y1238209D03*
Y1252382D03*
Y1266556D03*
X1113530Y1238209D03*
Y1252382D03*
Y1266556D03*
X1119042Y1238209D03*
Y1252382D03*
Y1266556D03*
X1127703Y1238209D03*
Y1252382D03*
Y1266556D03*
X1133215Y1238209D03*
Y1252382D03*
Y1266556D03*
X1095420Y1287816D03*
Y1301989D03*
Y1316162D03*
X1100932Y1287816D03*
Y1301989D03*
Y1316162D03*
X1109593Y1287816D03*
Y1301989D03*
Y1316162D03*
X1115105Y1287816D03*
Y1301989D03*
Y1316162D03*
X1123766Y1287816D03*
Y1301989D03*
Y1316162D03*
X1129278Y1287816D03*
Y1301989D03*
Y1316162D03*
X1099357Y1280729D03*
Y1294902D03*
Y1309075D03*
Y1323249D03*
X1104869Y1280729D03*
Y1294902D03*
Y1309075D03*
Y1323249D03*
X1113530Y1280729D03*
Y1294902D03*
Y1309075D03*
Y1323249D03*
X1119042Y1280729D03*
Y1294902D03*
Y1309075D03*
Y1323249D03*
X1127703Y1280729D03*
Y1294902D03*
Y1309075D03*
Y1323249D03*
X1133215Y1280729D03*
Y1294902D03*
Y1309075D03*
Y1323249D03*
X1095420Y1330335D03*
Y1344508D03*
Y1358682D03*
Y1372855D03*
X1100932Y1330335D03*
Y1344508D03*
Y1358682D03*
Y1372855D03*
X1109593Y1330335D03*
Y1344508D03*
Y1358682D03*
Y1372855D03*
X1115105Y1330335D03*
Y1344508D03*
Y1358682D03*
Y1372855D03*
X1123766Y1330335D03*
Y1344508D03*
Y1358682D03*
Y1372855D03*
X1129278Y1330335D03*
Y1344508D03*
Y1358682D03*
Y1372855D03*
X1099357Y1337422D03*
Y1351595D03*
Y1365768D03*
X1104869Y1337422D03*
Y1351595D03*
Y1365768D03*
X1113530Y1337422D03*
Y1351595D03*
Y1365768D03*
X1119042Y1337422D03*
Y1351595D03*
Y1365768D03*
X1127703Y1337422D03*
Y1351595D03*
Y1365768D03*
X1133215Y1337422D03*
Y1351595D03*
Y1365768D03*
X1095420Y1387028D03*
Y1401201D03*
X1100932Y1387028D03*
Y1401201D03*
X1109593Y1387028D03*
Y1401201D03*
X1115105Y1387028D03*
Y1401201D03*
X1123766Y1387028D03*
Y1401201D03*
X1129278Y1387028D03*
Y1401201D03*
X1099357Y1379942D03*
Y1394115D03*
Y1408288D03*
X1104869Y1379942D03*
Y1394115D03*
Y1408288D03*
X1113530Y1379942D03*
Y1394115D03*
Y1408288D03*
X1119042Y1379942D03*
Y1394115D03*
Y1408288D03*
X1127703Y1379942D03*
Y1394115D03*
Y1408288D03*
X1133215Y1379942D03*
Y1394115D03*
Y1408288D03*
X1398228Y63977D03*
X1412402D03*
X1426575D03*
X1398228Y116339D03*
Y96654D03*
Y102166D03*
Y110827D03*
X1412402Y116339D03*
X1426575D03*
X1405315Y114764D03*
X1419488D03*
X1412402Y96654D03*
X1426575D03*
X1412402Y102166D03*
X1426575D03*
X1405315Y100591D03*
X1419488D03*
X1405315Y106103D03*
X1419488D03*
X1412402Y110827D03*
X1426575D03*
X1405315Y120276D03*
X1419488D03*
X1440748Y63977D03*
X1433661Y114764D03*
X1440748Y116339D03*
X1447835Y114764D03*
X1433661Y100591D03*
Y106103D03*
X1440748Y96654D03*
Y102166D03*
X1447835Y100591D03*
Y106103D03*
X1440748Y110827D03*
X1433661Y120276D03*
X1447835D03*
X1483268Y63977D03*
X1511614D03*
X1497441D03*
X1483268Y116339D03*
Y110827D03*
Y102166D03*
Y96654D03*
X1518701Y114764D03*
X1504528D03*
X1490354D03*
X1511614Y116339D03*
X1497441D03*
X1511614Y110827D03*
X1497441D03*
X1518701Y106103D03*
X1504528D03*
X1490354D03*
X1518701Y100591D03*
X1504528D03*
X1490354D03*
X1511614Y102166D03*
X1497441D03*
X1511614Y96654D03*
X1497441D03*
X1518701Y120276D03*
X1504528D03*
X1490354D03*
X1525787Y63977D03*
X1532874Y114764D03*
X1525787Y116339D03*
Y110827D03*
X1532874Y106103D03*
Y100591D03*
X1525787Y102166D03*
Y96654D03*
X1532874Y120276D03*
G54D34*
X521850Y124507D03*
G54D11*
X24508Y5500D03*
X5500Y61492D03*
Y56492D03*
Y51492D03*
Y46492D03*
Y41492D03*
Y66492D03*
Y81492D03*
Y76492D03*
Y96492D03*
Y91492D03*
Y86492D03*
Y71492D03*
Y101492D03*
Y111492D03*
Y116492D03*
Y106492D03*
Y126492D03*
Y121492D03*
Y141492D03*
Y151492D03*
Y161492D03*
Y156492D03*
Y146492D03*
Y131492D03*
Y136492D03*
Y181492D03*
Y191492D03*
Y201492D03*
Y211492D03*
Y171492D03*
Y206492D03*
Y196492D03*
Y176492D03*
Y166492D03*
Y186492D03*
Y231492D03*
Y241492D03*
Y251492D03*
Y261492D03*
Y221492D03*
Y256492D03*
Y246492D03*
Y226492D03*
Y216492D03*
Y236492D03*
Y281492D03*
Y291492D03*
Y301492D03*
Y271492D03*
Y306492D03*
Y296492D03*
Y286492D03*
Y276492D03*
Y266492D03*
Y331492D03*
Y341492D03*
Y351492D03*
Y311492D03*
Y321492D03*
Y356492D03*
Y346492D03*
Y336492D03*
Y326492D03*
Y316492D03*
Y381492D03*
Y391492D03*
Y401492D03*
Y361492D03*
Y371492D03*
Y406492D03*
Y396492D03*
Y386492D03*
Y376492D03*
Y366492D03*
Y451492D03*
Y441492D03*
Y431492D03*
Y421492D03*
Y411492D03*
Y416492D03*
Y436492D03*
Y446492D03*
Y426492D03*
Y501492D03*
Y456492D03*
Y496492D03*
Y531492D03*
Y551492D03*
Y541492D03*
Y521492D03*
Y511492D03*
Y536492D03*
Y546492D03*
Y506492D03*
Y516492D03*
Y526492D03*
Y581492D03*
Y591492D03*
Y571492D03*
Y561492D03*
Y586492D03*
Y596492D03*
Y556492D03*
Y566492D03*
Y576492D03*
Y631492D03*
Y641492D03*
Y621492D03*
Y611492D03*
Y601492D03*
Y636492D03*
Y646492D03*
Y606492D03*
Y616492D03*
Y626492D03*
Y681492D03*
Y691492D03*
Y671492D03*
Y661492D03*
Y651492D03*
Y686492D03*
Y696492D03*
Y656492D03*
Y666492D03*
Y676492D03*
Y731492D03*
Y741492D03*
Y721492D03*
Y711492D03*
Y701492D03*
Y736492D03*
Y706492D03*
Y716492D03*
Y726492D03*
Y781492D03*
Y791492D03*
Y771492D03*
Y761492D03*
Y751492D03*
Y786492D03*
Y746492D03*
Y756492D03*
Y766492D03*
Y776492D03*
Y831492D03*
Y841492D03*
Y821492D03*
Y811492D03*
Y801492D03*
Y836492D03*
Y796492D03*
Y806492D03*
Y816492D03*
Y826492D03*
Y881492D03*
Y871492D03*
Y861492D03*
Y851492D03*
Y886492D03*
Y846492D03*
Y856492D03*
Y866492D03*
Y876492D03*
Y931492D03*
Y921492D03*
Y911492D03*
Y901492D03*
Y891492D03*
Y936492D03*
Y896492D03*
Y906492D03*
Y916492D03*
Y926492D03*
Y976492D03*
Y981492D03*
Y986492D03*
Y966492D03*
Y956492D03*
Y961492D03*
Y971492D03*
Y951492D03*
Y941492D03*
Y946492D03*
Y991492D03*
Y996492D03*
Y1001492D03*
Y1006492D03*
Y1026492D03*
Y1016492D03*
Y1011492D03*
Y1021492D03*
Y1031492D03*
Y1036492D03*
Y1066492D03*
Y1056492D03*
Y1046492D03*
Y1041492D03*
Y1051492D03*
Y1061492D03*
Y1071492D03*
Y1081492D03*
Y1076492D03*
Y1121492D03*
Y1131492D03*
Y1111492D03*
Y1101492D03*
Y1091492D03*
Y1086492D03*
Y1096492D03*
Y1106492D03*
Y1116492D03*
Y1126492D03*
Y1171492D03*
Y1161492D03*
Y1151492D03*
Y1141492D03*
Y1136492D03*
Y1146492D03*
Y1156492D03*
Y1166492D03*
Y1176492D03*
Y1221492D03*
Y1211492D03*
Y1201492D03*
Y1191492D03*
Y1181492D03*
Y1186492D03*
Y1196492D03*
Y1206492D03*
Y1216492D03*
Y1226492D03*
Y1271492D03*
Y1261492D03*
Y1251492D03*
Y1241492D03*
Y1231492D03*
Y1236492D03*
Y1246492D03*
Y1256492D03*
Y1266492D03*
Y1276492D03*
Y1321492D03*
Y1311492D03*
Y1301492D03*
Y1291492D03*
Y1281492D03*
Y1286492D03*
Y1296492D03*
Y1306492D03*
Y1316492D03*
X8983Y1368303D03*
X13983D03*
X18983D03*
X23983D03*
X5500Y1361492D03*
Y1351492D03*
Y1341492D03*
Y1331492D03*
Y1336492D03*
Y1346492D03*
Y1356492D03*
Y1326492D03*
X29508Y5500D03*
X39508D03*
X34508D03*
X44508D03*
X64508D03*
X69508D03*
X54508D03*
X49508D03*
X59508D03*
X28983Y1368303D03*
X33983D03*
X38983D03*
X43983D03*
X48983D03*
X53983D03*
X58983D03*
X63983D03*
X68983D03*
X114508Y5500D03*
X119508D03*
X104508D03*
X94508D03*
X84508D03*
X74508D03*
X79508D03*
X89508D03*
X99508D03*
X109508D03*
X83100Y984800D03*
X78600D03*
X83100Y980300D03*
X78600D03*
Y989300D03*
X83100D03*
X73983Y1368303D03*
X78983D03*
X83983D03*
X88983D03*
X93983D03*
X98983D03*
X107374Y1369303D03*
X112374D03*
X117374D03*
X134508Y5500D03*
X124508D03*
X129508D03*
X169508D03*
X159508D03*
X149508D03*
X139508D03*
X154508D03*
X164508D03*
X144508D03*
X141978Y958572D03*
X142006Y978425D03*
X122374Y1369303D03*
X127374D03*
X132374D03*
X137374D03*
X142374D03*
X147374D03*
X152374D03*
X157374D03*
X162374D03*
X167374D03*
X209508Y5500D03*
X199508D03*
X189508D03*
X179508D03*
X204508D03*
X214508D03*
X174508D03*
X184508D03*
X194508D03*
X209863Y566625D03*
X199102Y969717D03*
Y974717D03*
X183584Y974789D03*
Y969789D03*
X199392Y985113D03*
X183551Y984789D03*
X212063Y976725D03*
X203063D03*
X207563D03*
X216563D03*
X212063Y981725D03*
X216563D03*
X207563D03*
X203063D03*
X199392Y990113D03*
X183551Y989789D03*
X172374Y1369303D03*
X177374D03*
X182374D03*
X187374D03*
X192374D03*
X197374D03*
X202374D03*
X207374D03*
X212374D03*
X217374D03*
X259508Y5500D03*
X249508D03*
X239508D03*
X229508D03*
X219508D03*
X224508D03*
X234508D03*
X244508D03*
X254508D03*
X264508D03*
X250650Y556997D03*
Y561997D03*
X265545Y556794D03*
Y561794D03*
X250661Y572936D03*
Y577936D03*
X265590Y572801D03*
Y577801D03*
X225563Y976725D03*
X221063D03*
X225563Y981725D03*
X221063D03*
X222374Y1369303D03*
X227374D03*
X232374D03*
X237374D03*
X242374D03*
X247374D03*
X252374D03*
X257374D03*
X262374D03*
X309508Y5500D03*
X299508D03*
X289508D03*
X279508D03*
X269508D03*
X304508D03*
X314508D03*
X274508D03*
X284508D03*
X294508D03*
X269763Y569725D03*
X287763D03*
X292263D03*
X274263D03*
X283263D03*
X278763D03*
X283263Y564725D03*
X287763D03*
X292263D03*
X274263D03*
X269763D03*
X278763D03*
X267374Y1369303D03*
X272374D03*
X277374D03*
X282374D03*
X287374D03*
X292374D03*
X297374D03*
X302374D03*
X307374D03*
X312374D03*
X359508Y5500D03*
X349508D03*
X339508D03*
X329508D03*
X319508D03*
X324508D03*
X334508D03*
X344508D03*
X354508D03*
X333983Y1368303D03*
X338983D03*
X343983D03*
X348983D03*
X353983D03*
X358983D03*
X363983D03*
X317374Y1369303D03*
X322374D03*
X327374D03*
X395075Y18639D03*
Y13639D03*
X389508Y5500D03*
X379508D03*
X369508D03*
X364508D03*
X374508D03*
X384508D03*
X394508D03*
X395075Y43639D03*
Y38639D03*
Y33639D03*
Y28639D03*
Y23639D03*
X399000Y62000D03*
X396000Y55500D03*
X396075Y50248D03*
X368983Y1368303D03*
X373983D03*
X378983D03*
X383983D03*
X388983D03*
X393983D03*
X398983D03*
X403983D03*
X408983D03*
X413983D03*
X418983D03*
X423983D03*
X428983D03*
X433983D03*
X438983D03*
X443983D03*
X448983D03*
X453983D03*
X458983D03*
X463983D03*
X468983D03*
X473983D03*
X478983D03*
X483983D03*
X488983D03*
X493983D03*
X498983D03*
X503983D03*
X508983D03*
X517374Y1369303D03*
X522374D03*
X527374D03*
X532374D03*
X537374D03*
X542374D03*
X547374D03*
X552374D03*
X557374D03*
X597051Y7699D03*
Y12699D03*
Y17699D03*
X604146Y5500D03*
X597051Y22699D03*
Y27699D03*
Y32699D03*
Y37699D03*
Y42699D03*
X589000Y64000D03*
X594000Y61500D03*
X596000Y56500D03*
X596051Y51090D03*
X567374Y1369303D03*
X572374D03*
X577374D03*
X582374D03*
X587374D03*
X592374D03*
X597374D03*
X602374D03*
X562374D03*
X609146Y5500D03*
X619146D03*
X614146D03*
X629146D03*
X639146D03*
X649146D03*
X654146D03*
X644146D03*
X634146D03*
X624146D03*
X617374Y1369303D03*
X622374D03*
X627374D03*
X632374D03*
X637374D03*
X642374D03*
X647374D03*
X652374D03*
X607374D03*
X612374D03*
X679146Y5500D03*
X689146D03*
X694146D03*
X684146D03*
X659146D03*
X669146D03*
X664146D03*
X674146D03*
X699146D03*
X675913Y586555D03*
Y592955D03*
Y598155D03*
X672082Y582834D03*
X666882D03*
X661682D03*
X656482D03*
X669482Y613934D03*
Y609734D03*
X665282D03*
Y613934D03*
X661082D03*
Y609734D03*
X656882Y613934D03*
Y609734D03*
X675913Y603355D03*
X702483Y945989D03*
X667374Y1369303D03*
X672374D03*
X677374D03*
X682374D03*
X687374D03*
X692374D03*
X697374D03*
X702374D03*
X657374D03*
X662374D03*
X749146Y5500D03*
X709146D03*
X719146D03*
X729146D03*
X739146D03*
X744146D03*
X734146D03*
X724146D03*
X714146D03*
X704146D03*
X704399Y626799D03*
Y618399D03*
Y622599D03*
X721552Y951317D03*
X725852Y951067D03*
X747374Y1369303D03*
X742374D03*
X717374D03*
X722374D03*
X727374D03*
X732374D03*
X737374D03*
X707374D03*
X712374D03*
X795969Y-1374D03*
X759146Y5500D03*
X769146D03*
X774146D03*
X764146D03*
X754146D03*
X779146D03*
X755500Y1374500D03*
X752500Y1370500D03*
X757287Y1380873D03*
Y1385873D03*
Y1390873D03*
Y1395873D03*
Y1400873D03*
Y1405873D03*
Y1410873D03*
Y1415873D03*
Y1420873D03*
Y1425873D03*
Y1430873D03*
Y1435873D03*
Y1440873D03*
Y1445873D03*
X766156Y1462004D03*
X771156D03*
X790500Y1466500D03*
X786000Y1463500D03*
X756287Y1459264D03*
Y1454264D03*
X779547Y1463004D03*
X792902Y1477964D03*
Y1487964D03*
Y1497964D03*
Y1507964D03*
Y1517964D03*
Y1512964D03*
Y1472964D03*
Y1482964D03*
Y1492964D03*
Y1502964D03*
Y1562964D03*
Y1527964D03*
Y1537964D03*
Y1547964D03*
Y1557964D03*
Y1567964D03*
Y1522964D03*
Y1532964D03*
Y1542964D03*
Y1552964D03*
Y1612964D03*
Y1602964D03*
Y1592964D03*
Y1582964D03*
Y1572964D03*
Y1577964D03*
Y1587964D03*
Y1597964D03*
Y1607964D03*
X797902Y1652964D03*
X792902D03*
Y1642964D03*
Y1632964D03*
Y1622964D03*
Y1627964D03*
Y1637964D03*
Y1647964D03*
Y1617964D03*
X872642Y-140575D03*
Y-135575D03*
Y-130575D03*
Y-125575D03*
X890264Y-147256D03*
X880264D03*
X875264D03*
X885264D03*
X895264D03*
X872642Y-80575D03*
Y-120575D03*
Y-115575D03*
Y-110575D03*
Y-105575D03*
Y-100575D03*
Y-95575D03*
Y-90575D03*
Y-85575D03*
Y-30575D03*
Y-35575D03*
Y-40575D03*
Y-45575D03*
Y-50575D03*
Y-55575D03*
Y-60575D03*
Y-65575D03*
Y-70575D03*
Y-75575D03*
Y-20575D03*
Y-25575D03*
X940264Y-147256D03*
X930264D03*
X925264D03*
X935264D03*
X920264D03*
X910264D03*
X900264D03*
X905264D03*
X915264D03*
X960264D03*
X950264D03*
X955264D03*
X965264D03*
X945264D03*
X990264D03*
X980264D03*
X970264D03*
X975264D03*
X985264D03*
X1010264D03*
X1000264D03*
X1005264D03*
X1015264D03*
X995264D03*
X1040264D03*
X1030264D03*
X1020264D03*
X1025264D03*
X1035264D03*
X1060264D03*
X1050264D03*
X1055264D03*
X1065264D03*
X1045264D03*
X1080264D03*
X1070264D03*
X1075264D03*
X1085264D03*
X1078098Y1652768D03*
X1073098D03*
X1083098D03*
X1088098D03*
X1110264Y-147256D03*
X1100264D03*
X1090264D03*
X1105264D03*
X1095264D03*
X1130264D03*
X1120264D03*
X1115264D03*
X1125264D03*
X1135264D03*
X1093098Y1652768D03*
X1133098D03*
X1123098D03*
X1113098D03*
X1103098D03*
X1108098D03*
X1118098D03*
X1128098D03*
X1098098D03*
X1170264Y-147256D03*
X1155264D03*
X1175602Y-137594D03*
Y-127594D03*
X1160264Y-147256D03*
X1150264D03*
X1140264D03*
X1145264D03*
X1175602Y-132594D03*
Y-142594D03*
X1165264Y-147256D03*
X1175602Y-117594D03*
Y-107594D03*
Y-97594D03*
Y-87594D03*
Y-77594D03*
Y-82594D03*
Y-92594D03*
Y-102594D03*
Y-112594D03*
Y-122594D03*
Y-67594D03*
Y-57594D03*
Y-47594D03*
Y-37594D03*
Y-32594D03*
Y-42594D03*
Y-52594D03*
Y-62594D03*
Y-72594D03*
Y-17594D03*
Y-27594D03*
X1180500Y4000D03*
X1176500Y-500D03*
X1175602Y-22594D03*
Y-12594D03*
Y-7594D03*
X1162000Y1371500D03*
X1169783Y1369303D03*
X1179783D03*
X1174783D03*
X1184783D03*
X1158673Y1377067D03*
Y1422067D03*
Y1442067D03*
Y1452067D03*
X1158500Y1468500D03*
X1158673Y1457067D03*
Y1447067D03*
Y1437067D03*
Y1427067D03*
Y1462067D03*
Y1432067D03*
X1161000Y1474500D03*
X1166673Y1477941D03*
X1171673D03*
X1181673D03*
X1176673D03*
X1143098Y1652768D03*
X1183098D03*
X1173098D03*
X1163098D03*
X1153098D03*
X1158098D03*
X1168098D03*
X1178098D03*
X1138098D03*
X1148098D03*
X1191382Y5500D03*
X1196382D03*
X1186382D03*
X1201382D03*
X1211382D03*
X1221382D03*
X1231382D03*
X1226382D03*
X1216382D03*
X1206382D03*
X1199783Y1369303D03*
X1209783D03*
X1219783D03*
X1229783D03*
X1189783D03*
X1224783D03*
X1214783D03*
X1204783D03*
X1194783D03*
X1191673Y1477941D03*
X1201673D03*
X1214972Y1482642D03*
Y1517642D03*
Y1487642D03*
Y1497642D03*
Y1507642D03*
Y1512642D03*
Y1502642D03*
Y1492642D03*
X1206673Y1477941D03*
X1196673D03*
X1186673D03*
X1211673D03*
X1214972Y1567642D03*
Y1527642D03*
Y1537642D03*
Y1547642D03*
Y1557642D03*
Y1562642D03*
Y1552642D03*
Y1542642D03*
Y1532642D03*
Y1522642D03*
Y1577642D03*
Y1587642D03*
Y1597642D03*
Y1607642D03*
Y1612642D03*
Y1602642D03*
Y1592642D03*
Y1582642D03*
Y1572642D03*
Y1617642D03*
Y1627642D03*
Y1637642D03*
X1213098Y1652768D03*
X1193098D03*
X1203098D03*
X1208098D03*
X1214972Y1642642D03*
Y1632642D03*
X1188098Y1652768D03*
X1198098D03*
X1214972Y1622642D03*
Y1647642D03*
X1251382Y5500D03*
X1261382D03*
X1271382D03*
X1281382D03*
X1276382D03*
X1266382D03*
X1256382D03*
X1241382D03*
X1246382D03*
X1236382D03*
X1249783Y1369303D03*
X1259783D03*
X1269783D03*
X1279783D03*
X1239783D03*
X1274783D03*
X1264783D03*
X1254783D03*
X1234783D03*
X1244783D03*
X1301382Y5500D03*
X1311382D03*
X1296382D03*
X1316382D03*
X1306382D03*
X1291382D03*
X1286382D03*
X1326382D03*
X1321382D03*
X1299783Y1369303D03*
X1309783D03*
X1319783D03*
X1329783D03*
X1289783D03*
X1324783D03*
X1314783D03*
X1304783D03*
X1294783D03*
X1284783D03*
X1363579Y19821D03*
Y14821D03*
Y9821D03*
X1351382Y5500D03*
X1356382D03*
X1346382D03*
X1336382D03*
X1341382D03*
X1331382D03*
X1363579Y44821D03*
Y39821D03*
Y34821D03*
Y29821D03*
Y24821D03*
X1374000Y64500D03*
X1363579Y51618D03*
X1370200Y550500D03*
X1366000D03*
X1375900Y568500D03*
X1366000Y563100D03*
X1370200D03*
Y554700D03*
X1366000D03*
X1370200Y558900D03*
X1366000D03*
X1373700Y582900D03*
X1369500D03*
X1377900Y587100D03*
Y591300D03*
Y595500D03*
X1373700D03*
Y591300D03*
Y587100D03*
X1369500Y595500D03*
Y591300D03*
Y587100D03*
X1377900Y599700D03*
X1373700D03*
X1369500D03*
X1349783Y1369303D03*
X1359783D03*
X1369783D03*
X1339783D03*
X1374783D03*
X1364783D03*
X1354783D03*
X1344783D03*
X1334783D03*
X1396500Y549500D03*
Y559900D03*
Y554700D03*
Y565100D03*
X1393000Y568500D03*
X1387300D03*
X1381600D03*
X1382100Y587100D03*
X1386300D03*
X1399783Y1369303D03*
X1409783D03*
X1419783D03*
X1379783D03*
X1389783D03*
X1404783D03*
X1414783D03*
X1424783D03*
X1394783D03*
X1384783D03*
X1434441Y590424D03*
X1434581Y586136D03*
X1449783Y1369303D03*
X1459783D03*
X1469783D03*
X1429783D03*
X1439783D03*
X1444783D03*
X1454783D03*
X1464783D03*
X1474783D03*
X1434783D03*
X1499783D03*
X1509783D03*
X1519783D03*
X1479783D03*
X1489783D03*
X1494783D03*
X1484783D03*
X1504783D03*
X1514783D03*
X1565555Y16517D03*
X1568030Y5500D03*
X1565555Y21517D03*
Y26517D03*
Y31517D03*
Y36517D03*
Y41517D03*
X1557000Y64500D03*
X1561500Y62000D03*
X1564000Y57500D03*
X1564555Y52124D03*
X1549783Y1369303D03*
X1559783D03*
X1569783D03*
X1529783D03*
X1539783D03*
X1524783D03*
X1534783D03*
X1544783D03*
X1554783D03*
X1564783D03*
X1603030Y5500D03*
X1613030D03*
X1573030D03*
X1583030D03*
X1593030D03*
X1618030D03*
X1608030D03*
X1598030D03*
X1588030D03*
X1578030D03*
X1614783Y1369303D03*
X1604783D03*
X1599783D03*
X1609783D03*
X1619783D03*
X1579783D03*
X1589783D03*
X1574783D03*
X1584783D03*
X1594783D03*
X1653030Y5500D03*
X1663030D03*
X1623030D03*
X1633030D03*
X1643030D03*
X1668030D03*
X1658030D03*
X1648030D03*
X1638030D03*
X1628030D03*
X1664783Y1369303D03*
X1654783D03*
X1644783D03*
X1634783D03*
X1624783D03*
X1649783D03*
X1659783D03*
X1629783D03*
X1639783D03*
X1703030Y5500D03*
X1713030D03*
X1673030D03*
X1683030D03*
X1693030D03*
X1718030D03*
X1708030D03*
X1698030D03*
X1688030D03*
X1678030D03*
X1714783Y1369303D03*
X1704783D03*
X1694783D03*
X1684783D03*
X1674783D03*
X1699783D03*
X1709783D03*
X1669783D03*
X1679783D03*
X1689783D03*
X1753030Y5500D03*
X1763030D03*
X1723030D03*
X1733030D03*
X1743030D03*
X1758030D03*
X1748030D03*
X1738030D03*
X1728030D03*
X1764783Y1369303D03*
X1754783D03*
X1744783D03*
X1734783D03*
X1724783D03*
X1749783D03*
X1759783D03*
X1719783D03*
X1729783D03*
X1739783D03*
X1778030Y5500D03*
X1793030D03*
X1803030D03*
X1813030D03*
X1808030D03*
X1798030D03*
X1783030D03*
X1788030D03*
X1773030D03*
X1768030D03*
X1783806Y989468D03*
X1804783Y1369303D03*
X1794783D03*
X1784783D03*
X1774783D03*
X1799783D03*
X1809783D03*
X1769783D03*
X1779783D03*
X1789783D03*
X1843030Y5500D03*
X1853030D03*
X1863030D03*
X1838030D03*
X1858030D03*
X1848030D03*
X1823030D03*
X1833030D03*
X1828030D03*
X1818030D03*
X1862652Y846508D03*
X1825741Y969210D03*
Y974210D03*
X1840683Y969318D03*
Y974318D03*
X1825744Y986011D03*
X1840578Y985885D03*
X1844863Y983125D03*
X1853863D03*
X1858363D03*
X1849363D03*
X1862863D03*
X1853863Y978125D03*
X1844863D03*
X1849363D03*
X1862863D03*
X1858363D03*
X1825744Y991011D03*
X1840578Y990885D03*
X1854783Y1369303D03*
X1844783D03*
X1834783D03*
X1824783D03*
X1814783D03*
X1849783D03*
X1859783D03*
X1819783D03*
X1829783D03*
X1839783D03*
X1878030Y5500D03*
X1883030D03*
X1873030D03*
X1868030D03*
X1909030D03*
X1888030D03*
X1873099Y817150D03*
X1878099D03*
X1873099Y821650D03*
X1878099D03*
X1873099Y826150D03*
X1878099D03*
X1877512Y831377D03*
X1882512D03*
X1865202Y831559D03*
X1873012Y831377D03*
X1878099Y812650D03*
X1873099D03*
X1878099Y808150D03*
X1873099D03*
X1878099Y803650D03*
X1873099D03*
X1878373Y846472D03*
X1883373D03*
X1867652Y846508D03*
X1867363Y983125D03*
Y978125D03*
X1904783Y1369303D03*
X1894783D03*
X1884783D03*
X1874783D03*
X1864783D03*
X1899783D03*
X1909783D03*
X1869783D03*
X1879783D03*
X1889783D03*
X1929343Y16525D03*
Y11525D03*
Y6525D03*
X1914030Y5500D03*
X1919030D03*
X1924030D03*
X1929343Y46525D03*
Y41525D03*
Y36525D03*
Y31525D03*
Y26525D03*
Y21525D03*
Y66525D03*
Y61525D03*
Y56525D03*
Y51525D03*
Y116525D03*
Y111525D03*
Y106525D03*
Y101525D03*
Y96525D03*
Y91525D03*
Y86525D03*
Y81525D03*
Y76525D03*
Y71525D03*
Y121525D03*
Y126525D03*
Y136525D03*
Y146525D03*
Y156525D03*
Y161525D03*
Y151525D03*
Y141525D03*
Y131525D03*
Y176525D03*
Y186525D03*
Y196525D03*
Y206525D03*
Y166525D03*
Y211525D03*
Y201525D03*
Y191525D03*
Y181525D03*
Y171525D03*
Y226525D03*
Y236525D03*
Y246525D03*
Y256525D03*
Y216525D03*
Y261525D03*
Y251525D03*
Y241525D03*
Y231525D03*
Y221525D03*
Y276525D03*
Y286525D03*
Y296525D03*
Y306525D03*
Y266525D03*
Y301525D03*
Y291525D03*
Y281525D03*
Y271525D03*
Y326525D03*
Y336525D03*
Y346525D03*
Y356525D03*
Y316525D03*
Y351525D03*
Y341525D03*
Y331525D03*
Y321525D03*
Y311525D03*
Y376525D03*
Y386525D03*
Y396525D03*
Y406525D03*
Y366525D03*
Y401525D03*
Y391525D03*
Y381525D03*
Y371525D03*
Y361525D03*
Y426525D03*
Y436525D03*
Y446525D03*
Y416525D03*
Y451525D03*
Y441525D03*
Y431525D03*
Y421525D03*
Y411525D03*
Y476525D03*
Y486525D03*
Y496525D03*
Y456525D03*
Y466525D03*
Y501525D03*
Y491525D03*
Y481525D03*
Y471525D03*
Y461525D03*
Y526525D03*
Y536525D03*
Y546525D03*
Y506525D03*
Y516525D03*
Y551525D03*
Y541525D03*
Y531525D03*
Y521525D03*
Y511525D03*
Y576525D03*
Y586525D03*
Y596525D03*
Y556525D03*
Y566525D03*
Y591525D03*
Y581525D03*
Y571525D03*
Y561525D03*
Y626525D03*
Y636525D03*
Y646525D03*
Y606525D03*
Y616525D03*
Y641525D03*
Y631525D03*
Y621525D03*
Y611525D03*
Y601525D03*
Y676525D03*
Y686525D03*
Y696525D03*
Y656525D03*
Y666525D03*
Y691525D03*
Y681525D03*
Y671525D03*
Y661525D03*
Y651525D03*
Y726525D03*
Y736525D03*
Y706525D03*
Y716525D03*
Y741525D03*
Y731525D03*
Y721525D03*
Y711525D03*
Y701525D03*
Y776525D03*
Y786525D03*
Y746525D03*
Y756525D03*
Y766525D03*
Y791525D03*
Y781525D03*
Y771525D03*
Y761525D03*
Y751525D03*
Y826525D03*
Y836525D03*
Y796525D03*
Y806525D03*
Y816525D03*
Y841525D03*
Y831525D03*
Y821525D03*
Y811525D03*
Y801525D03*
Y876525D03*
Y886525D03*
Y846525D03*
Y856525D03*
Y866525D03*
Y881525D03*
Y871525D03*
Y861525D03*
Y851525D03*
Y926525D03*
Y896525D03*
Y906525D03*
Y916525D03*
Y931525D03*
Y921525D03*
Y911525D03*
Y901525D03*
Y891525D03*
Y936525D03*
Y973863D03*
Y978863D03*
Y983863D03*
Y951525D03*
Y956525D03*
Y961525D03*
Y966525D03*
Y946525D03*
Y941525D03*
Y988863D03*
Y993863D03*
Y998863D03*
Y1003863D03*
Y1008863D03*
Y1033863D03*
Y1028863D03*
Y1023863D03*
Y1018863D03*
Y1013863D03*
Y1073863D03*
Y1083863D03*
Y1043863D03*
Y1053863D03*
Y1063863D03*
Y1078863D03*
Y1068863D03*
Y1058863D03*
Y1048863D03*
Y1038863D03*
Y1123863D03*
Y1093863D03*
Y1103863D03*
Y1113863D03*
Y1128863D03*
Y1118863D03*
Y1108863D03*
Y1098863D03*
Y1088863D03*
Y1173863D03*
Y1133863D03*
Y1143863D03*
Y1153863D03*
Y1163863D03*
Y1178863D03*
Y1168863D03*
Y1158863D03*
Y1148863D03*
Y1138863D03*
Y1223863D03*
Y1183863D03*
Y1193863D03*
Y1203863D03*
Y1213863D03*
Y1228863D03*
Y1218863D03*
Y1208863D03*
Y1198863D03*
Y1188863D03*
Y1273863D03*
Y1233863D03*
Y1243863D03*
Y1253863D03*
Y1263863D03*
Y1268863D03*
Y1258863D03*
Y1248863D03*
Y1238863D03*
Y1323863D03*
Y1283863D03*
Y1293863D03*
Y1303863D03*
Y1313863D03*
Y1318863D03*
Y1308863D03*
Y1298863D03*
Y1288863D03*
Y1278863D03*
Y1333863D03*
Y1343863D03*
Y1353863D03*
X1924783Y1369303D03*
X1914783D03*
X1919783D03*
X1929343Y1358863D03*
Y1348863D03*
Y1338863D03*
Y1328863D03*
Y1363863D03*
G54D21*
X111024Y302303D03*
Y755059D03*
Y1207815D03*
X235236Y302303D03*
Y755059D03*
Y1207815D03*
X359449Y302303D03*
Y755059D03*
Y1207815D03*
X483661Y302303D03*
Y755059D03*
Y1207815D03*
X607874Y302303D03*
Y755059D03*
Y1207815D03*
X732087Y302303D03*
Y755059D03*
Y1207815D03*
X1098524Y-115157D03*
X1281693Y302303D03*
Y755059D03*
Y1207815D03*
X1405906Y302303D03*
Y755059D03*
Y1207815D03*
X1530118Y302303D03*
Y755059D03*
Y1207815D03*
X1654331Y302303D03*
Y755059D03*
Y1207815D03*
X1778543Y302303D03*
Y755059D03*
Y1207815D03*
X1902756Y302303D03*
Y755059D03*
Y1207815D03*
G54D20*
X111024Y153681D03*
Y606437D03*
Y1059193D03*
X235236Y153681D03*
Y606437D03*
Y1059193D03*
X359449Y153681D03*
Y606437D03*
Y1059193D03*
X483661Y153681D03*
Y606437D03*
Y1059193D03*
X607874Y153681D03*
Y606437D03*
Y1059193D03*
X732087Y153681D03*
Y606437D03*
Y1059193D03*
X949902Y-115157D03*
X1281693Y153681D03*
Y606437D03*
Y1059193D03*
X1405906Y153681D03*
Y606437D03*
Y1059193D03*
X1530118Y153681D03*
Y606437D03*
Y1059193D03*
X1654331Y153681D03*
Y606437D03*
Y1059193D03*
X1778543Y153681D03*
Y606437D03*
Y1059193D03*
X1902756Y153681D03*
Y606437D03*
Y1059193D03*
G54D28*
X429724Y68307D03*
X458071D03*
X443898D03*
X429724Y87993D03*
Y82481D03*
Y73819D03*
X458071Y87993D03*
Y82481D03*
X450984Y91930D03*
Y86418D03*
X443898Y87993D03*
Y82481D03*
X436811Y91930D03*
Y86418D03*
X458071Y73819D03*
X450984Y77756D03*
Y72245D03*
X443898Y73819D03*
X436811Y77756D03*
Y72245D03*
X472244Y68307D03*
X479331Y91930D03*
Y86418D03*
X472244Y87993D03*
Y82481D03*
X465157Y91930D03*
Y86418D03*
X479331Y77756D03*
Y72245D03*
X472244Y73819D03*
X465157Y77756D03*
Y72245D03*
X514764Y68307D03*
X543110D03*
X528937D03*
X557283D03*
X514764Y87993D03*
Y82481D03*
Y73819D03*
X550197Y91930D03*
Y86418D03*
X543110Y87993D03*
Y82481D03*
X536024Y91930D03*
Y86418D03*
X528937Y87993D03*
Y82481D03*
X521850Y91930D03*
Y86418D03*
X550197Y77756D03*
Y72245D03*
X543110Y73819D03*
X536024Y77756D03*
Y72245D03*
X528937Y73819D03*
X521850Y77756D03*
Y72245D03*
X557283Y87993D03*
Y82481D03*
Y73819D03*
X564370Y91930D03*
Y86418D03*
Y77756D03*
Y72245D03*
X1398228Y68307D03*
X1426575D03*
X1412402D03*
X1398228Y87993D03*
Y82481D03*
Y73819D03*
X1426575Y87993D03*
Y82481D03*
X1419488Y91930D03*
Y86418D03*
X1412402Y87993D03*
Y82481D03*
X1405315Y91930D03*
Y86418D03*
X1426575Y73819D03*
X1419488Y77756D03*
Y72245D03*
X1412402Y73819D03*
X1405315Y77756D03*
Y72245D03*
X1440748Y68307D03*
X1447835Y91930D03*
Y86418D03*
X1440748Y87993D03*
Y82481D03*
X1433661Y91930D03*
Y86418D03*
X1447835Y77756D03*
Y72245D03*
X1440748Y73819D03*
X1433661Y77756D03*
Y72245D03*
X1483268Y68307D03*
X1511614D03*
X1497441D03*
X1483268Y87993D03*
Y82481D03*
Y73819D03*
X1518701Y91930D03*
Y86418D03*
X1511614Y87993D03*
Y82481D03*
X1504528Y91930D03*
Y86418D03*
X1497441Y87993D03*
Y82481D03*
X1490354Y91930D03*
Y86418D03*
X1518701Y77756D03*
Y72245D03*
X1511614Y73819D03*
X1504528Y77756D03*
Y72245D03*
X1497441Y73819D03*
X1490354Y77756D03*
Y72245D03*
X1525787Y68307D03*
X1532874Y91930D03*
Y86418D03*
X1525787Y87993D03*
Y82481D03*
X1532874Y77756D03*
Y72245D03*
X1525787Y73819D03*
G54D38*
X937205Y12599D03*
Y67717D03*
X929331Y48032D03*
Y32284D03*
X937205Y44095D03*
Y36221D03*
Y28347D03*
X929331Y103150D03*
Y87402D03*
Y71654D03*
X937205Y114961D03*
Y99213D03*
Y83465D03*
X929331Y166142D03*
Y150394D03*
Y134646D03*
Y118898D03*
X937205Y162205D03*
Y146457D03*
Y130709D03*
X929331Y213386D03*
Y197638D03*
Y181890D03*
X937205Y209449D03*
Y193701D03*
Y177953D03*
X929331Y260630D03*
Y244882D03*
Y229134D03*
X937205Y256693D03*
Y240945D03*
Y225197D03*
X929331Y307874D03*
Y292126D03*
Y276378D03*
X937205Y303937D03*
Y288189D03*
Y272441D03*
X929331Y323622D03*
X937205Y319685D03*
Y407480D03*
Y391732D03*
X929331Y450787D03*
X937205Y446850D03*
X929331Y427165D03*
Y419291D03*
Y411417D03*
X937205Y431102D03*
Y423228D03*
Y415354D03*
X929331Y498031D03*
Y482283D03*
Y466535D03*
X937205Y494094D03*
Y478346D03*
Y462598D03*
X929331Y545275D03*
Y529527D03*
Y513779D03*
X937205Y541338D03*
Y525590D03*
Y509842D03*
X929331Y592519D03*
Y576771D03*
Y561023D03*
X937205Y588582D03*
Y572834D03*
Y557086D03*
X929331Y639763D03*
Y624015D03*
Y608267D03*
X937205Y635826D03*
Y620078D03*
Y604330D03*
X929331Y687007D03*
Y671259D03*
Y655511D03*
X937205Y683070D03*
Y667322D03*
Y651574D03*
X929331Y702755D03*
X937205Y698818D03*
X954921Y63780D03*
X947047Y67717D03*
X954921Y40158D03*
Y32284D03*
X947047Y51969D03*
Y44095D03*
Y36221D03*
Y28347D03*
X954921Y111024D03*
Y95276D03*
Y79528D03*
X947047Y107087D03*
Y91339D03*
Y75591D03*
X954921Y158268D03*
Y142520D03*
Y126772D03*
X947047Y154331D03*
Y138583D03*
Y122835D03*
X954921Y205512D03*
Y189764D03*
Y174016D03*
X947047Y201575D03*
Y185827D03*
Y170079D03*
X954921Y252756D03*
Y237008D03*
Y221260D03*
X947047Y248819D03*
Y233071D03*
Y217323D03*
X954921Y300000D03*
Y284252D03*
Y268504D03*
X947047Y296063D03*
Y280315D03*
Y264567D03*
X954921Y339371D03*
Y331496D03*
Y315748D03*
X947047Y327559D03*
Y311811D03*
Y407480D03*
X954921Y442913D03*
X947047Y454724D03*
X954921Y427165D03*
Y419291D03*
Y411417D03*
X947047Y431102D03*
Y423228D03*
X954921Y490157D03*
Y474409D03*
Y458661D03*
X947047Y501968D03*
Y486220D03*
Y470472D03*
X954921Y553149D03*
Y537401D03*
Y521653D03*
Y505905D03*
X947047Y549212D03*
Y533464D03*
Y517716D03*
X954921Y600393D03*
Y584645D03*
Y568897D03*
X947047Y596456D03*
Y580708D03*
Y564960D03*
X954921Y647637D03*
Y631889D03*
Y616141D03*
X947047Y643700D03*
Y627952D03*
Y612204D03*
X954921Y694881D03*
Y679133D03*
Y663385D03*
X947047Y690944D03*
Y675196D03*
Y659448D03*
X954921Y710629D03*
X947047Y706692D03*
X1105315Y12599D03*
X1123031Y63780D03*
X1115157Y67717D03*
X1105315D03*
X1123031Y40158D03*
Y32284D03*
X1097441Y48032D03*
Y32284D03*
X1115157Y51969D03*
Y44095D03*
Y36221D03*
Y28347D03*
X1105315Y44095D03*
Y36221D03*
Y28347D03*
X1123031Y111024D03*
Y95276D03*
Y79528D03*
X1097441Y103150D03*
Y87402D03*
Y71654D03*
X1115157Y107087D03*
Y91339D03*
Y75591D03*
X1105315Y114961D03*
Y99213D03*
Y83465D03*
X1123031Y158268D03*
Y142520D03*
Y126772D03*
X1097441Y166142D03*
Y150394D03*
Y134646D03*
Y118898D03*
X1115157Y154331D03*
Y138583D03*
Y122835D03*
X1105315Y162205D03*
Y146457D03*
Y130709D03*
X1123031Y205512D03*
Y189764D03*
Y174016D03*
X1097441Y213386D03*
Y197638D03*
Y181890D03*
X1115157Y201575D03*
Y185827D03*
Y170079D03*
X1105315Y209449D03*
Y193701D03*
Y177953D03*
X1123031Y252756D03*
Y237008D03*
Y221260D03*
X1097441Y260630D03*
Y244882D03*
Y229134D03*
X1115157Y248819D03*
Y233071D03*
Y217323D03*
X1105315Y256693D03*
Y240945D03*
Y225197D03*
X1123031Y300000D03*
Y284252D03*
Y268504D03*
X1097441Y307874D03*
Y292126D03*
Y276378D03*
X1115157Y296063D03*
Y280315D03*
Y264567D03*
X1105315Y303937D03*
Y288189D03*
Y272441D03*
X1123031Y339371D03*
Y331496D03*
Y315748D03*
X1097441Y323622D03*
X1115157Y327559D03*
Y311811D03*
X1105315Y319685D03*
X1115157Y407480D03*
X1105315D03*
Y391732D03*
X1123031Y442913D03*
X1097441Y450787D03*
X1115157Y454724D03*
X1105315Y446850D03*
X1123031Y427165D03*
Y419291D03*
Y411417D03*
X1097441Y427165D03*
Y419291D03*
Y411417D03*
X1115157Y431102D03*
Y423228D03*
X1105315Y431102D03*
Y423228D03*
Y415354D03*
X1123031Y490157D03*
Y474409D03*
Y458661D03*
X1097441Y498031D03*
Y482283D03*
Y466535D03*
X1115157Y501968D03*
Y486220D03*
Y470472D03*
X1105315Y494094D03*
Y478346D03*
Y462598D03*
X1123031Y553149D03*
Y537401D03*
Y521653D03*
Y505905D03*
X1097441Y545275D03*
Y529527D03*
Y513779D03*
X1115157Y549212D03*
Y533464D03*
Y517716D03*
X1105315Y541338D03*
Y525590D03*
Y509842D03*
X1123031Y600393D03*
Y584645D03*
Y568897D03*
X1097441Y592519D03*
Y576771D03*
Y561023D03*
X1115157Y596456D03*
Y580708D03*
Y564960D03*
X1105315Y588582D03*
Y572834D03*
Y557086D03*
X1123031Y647637D03*
Y631889D03*
Y616141D03*
X1097441Y639763D03*
Y624015D03*
Y608267D03*
X1115157Y643700D03*
Y627952D03*
Y612204D03*
X1105315Y635826D03*
Y620078D03*
Y604330D03*
X1123031Y694881D03*
Y679133D03*
Y663385D03*
X1097441Y687007D03*
Y671259D03*
Y655511D03*
X1115157Y690944D03*
Y675196D03*
Y659448D03*
X1105315Y683070D03*
Y667322D03*
Y651574D03*
X1123031Y710629D03*
X1097441Y702755D03*
X1115157Y706692D03*
X1105315Y698818D03*
G54D42*
X986614Y1619764D03*
X974016D03*
Y1597126D03*
X986614D03*
X974016Y1591220D03*
Y1603031D03*
Y1613858D03*
X986614Y1591220D03*
Y1613858D03*
Y1603031D03*
X974016Y1642401D03*
X986614D03*
X974016Y1625669D03*
Y1636496D03*
Y1648307D03*
X986614Y1625669D03*
Y1636496D03*
Y1648307D03*
X1002362Y1597126D03*
X1014961D03*
X1030709D03*
X1002362Y1591220D03*
Y1603031D03*
X1014961Y1591220D03*
Y1603031D03*
X1030709Y1591220D03*
Y1603031D03*
X1043307Y1597126D03*
Y1591220D03*
Y1603031D03*
X1101457Y1588583D03*
X1119685D03*
X1108150D03*
X1126378D03*
G54D30*
X450984Y124507D03*
X436811D03*
X479830D03*
X465157D03*
X550197D03*
X536023D03*
X564370D03*
X766707Y872260D03*
X762453Y872413D03*
X765025Y867802D03*
X874715Y707651D03*
X871115D03*
X867515D03*
X884700Y705200D03*
X881100D03*
X877500D03*
X929331Y16536D03*
X937205Y20473D03*
X929331Y63780D03*
Y40158D03*
Y24410D03*
X937205Y51969D03*
X929331Y111024D03*
Y95276D03*
Y79528D03*
X937205Y107087D03*
Y91339D03*
Y75591D03*
X929331Y158268D03*
Y142520D03*
Y126772D03*
X937205Y154331D03*
Y138583D03*
Y122835D03*
X929331Y205512D03*
Y189764D03*
Y174016D03*
X937205Y201575D03*
Y185827D03*
Y170079D03*
X929331Y252756D03*
Y237008D03*
Y221260D03*
X937205Y248819D03*
Y233071D03*
Y217323D03*
X929331Y300000D03*
Y284252D03*
Y268504D03*
X937205Y296063D03*
Y280315D03*
Y264567D03*
X929331Y339371D03*
Y331496D03*
Y315748D03*
X937205Y335434D03*
Y327559D03*
Y311811D03*
X929331Y403543D03*
Y395669D03*
X937205Y399606D03*
X929331Y442913D03*
X937205Y454724D03*
X929331Y490157D03*
Y474409D03*
Y458661D03*
X937205Y501968D03*
Y486220D03*
Y470472D03*
X929331Y553149D03*
Y537401D03*
Y521653D03*
Y505905D03*
X937205Y549212D03*
Y533464D03*
Y517716D03*
X929331Y600393D03*
Y584645D03*
Y568897D03*
X937205Y596456D03*
Y580708D03*
Y564960D03*
X929331Y647637D03*
Y631889D03*
Y616141D03*
X937205Y643700D03*
Y627952D03*
Y612204D03*
X929331Y694881D03*
Y679133D03*
Y663385D03*
X937205Y690944D03*
Y675196D03*
Y659448D03*
X929331Y718504D03*
Y710629D03*
X937205Y714567D03*
Y706692D03*
X954921Y16536D03*
X947047Y20473D03*
Y12599D03*
X954921Y48032D03*
Y24410D03*
Y103150D03*
Y87402D03*
Y71654D03*
X947047Y114961D03*
Y99213D03*
Y83465D03*
X954921Y166142D03*
Y150394D03*
Y134646D03*
Y118898D03*
X947047Y162205D03*
Y146457D03*
Y130709D03*
X990565Y130230D03*
Y135230D03*
Y125230D03*
X954921Y213386D03*
Y197638D03*
Y181890D03*
X947047Y209449D03*
Y193701D03*
Y177953D03*
X954921Y260630D03*
Y244882D03*
Y229134D03*
X947047Y256693D03*
Y240945D03*
Y225197D03*
X954921Y307874D03*
Y292126D03*
Y276378D03*
X947047Y303937D03*
Y288189D03*
Y272441D03*
X954921Y323622D03*
X947047Y335434D03*
Y319685D03*
X954921Y403543D03*
Y395669D03*
X947047Y399606D03*
Y391732D03*
X954921Y450787D03*
X947047Y446850D03*
Y415354D03*
X954921Y498031D03*
Y482283D03*
Y466535D03*
X947047Y494094D03*
Y478346D03*
Y462598D03*
X954921Y545275D03*
Y529527D03*
Y513779D03*
X947047Y541338D03*
Y525590D03*
Y509842D03*
X954921Y592519D03*
Y576771D03*
Y561023D03*
X947047Y588582D03*
Y572834D03*
Y557086D03*
X954921Y639763D03*
Y624015D03*
Y608267D03*
X947047Y635826D03*
Y620078D03*
Y604330D03*
X954921Y687007D03*
Y671259D03*
Y655511D03*
X947047Y683070D03*
Y667322D03*
Y651574D03*
X954921Y718504D03*
Y702755D03*
X947047Y714567D03*
Y698818D03*
X1030775Y130016D03*
X1030890Y137780D03*
X993565Y137730D03*
Y132730D03*
Y127730D03*
X1030774Y133840D03*
X1030758Y126274D03*
X1030825Y122335D03*
X1000500Y1511400D03*
X1026106Y1545595D03*
Y1539995D03*
X1031706Y1545595D03*
Y1539995D03*
X1020574Y1540059D03*
Y1545659D03*
X1039758Y1559605D03*
X1014974Y1540059D03*
Y1545659D03*
X1039358Y1565405D03*
X1033717Y1563634D03*
X1028223Y1563763D03*
X1022623D03*
X1017023D03*
X1011476Y1565175D03*
X1005658Y1565005D03*
X1000058D03*
X1039958Y1553705D03*
Y1548105D03*
Y1542505D03*
X1039358Y1571005D03*
Y1576605D03*
X1005658Y1575905D03*
X1033917Y1574834D03*
X1033717Y1569234D03*
X1000058Y1575905D03*
X1028423Y1574963D03*
X1028223Y1569363D03*
X994460Y1577240D03*
X1022823Y1574963D03*
X1022623Y1569363D03*
X1017223Y1574963D03*
X1017023Y1569363D03*
X1011676Y1576375D03*
X1011476Y1570775D03*
X1005658Y1570605D03*
X1000058D03*
X1078100Y392600D03*
Y397600D03*
Y402600D03*
X1072600Y392500D03*
Y397500D03*
Y402500D03*
Y407500D03*
X1078100Y407600D03*
X1041810Y1511084D03*
X1055310D03*
X1059810D03*
X1064310D03*
X1068810D03*
X1073310D03*
X1078358Y1561105D03*
Y1566705D03*
X1072758Y1561105D03*
Y1566705D03*
X1067158Y1561105D03*
Y1566705D03*
X1061558Y1561105D03*
Y1566705D03*
X1055768Y1566675D03*
X1055418Y1560785D03*
X1055618Y1554885D03*
Y1549285D03*
Y1543685D03*
X1078358Y1572305D03*
X1072758D03*
X1067158D03*
X1061558D03*
X1055768Y1572275D03*
Y1577875D03*
X1123031Y16536D03*
X1097441D03*
X1115157Y20473D03*
Y12599D03*
X1105315Y20473D03*
X1097441Y63780D03*
X1123031Y48032D03*
Y24410D03*
X1097441Y40158D03*
Y24410D03*
X1105315Y51969D03*
X1123031Y103150D03*
Y87402D03*
Y71654D03*
X1097441Y111024D03*
Y95276D03*
Y79528D03*
X1115157Y114961D03*
Y99213D03*
Y83465D03*
X1105315Y107087D03*
Y91339D03*
Y75591D03*
X1123031Y166142D03*
Y150394D03*
Y134646D03*
Y118898D03*
X1097441Y158268D03*
Y142520D03*
Y126772D03*
X1115157Y162205D03*
Y146457D03*
Y130709D03*
X1105315Y154331D03*
Y138583D03*
Y122835D03*
X1123031Y213386D03*
Y197638D03*
Y181890D03*
X1097441Y205512D03*
Y189764D03*
Y174016D03*
X1115157Y209449D03*
Y193701D03*
Y177953D03*
X1105315Y201575D03*
Y185827D03*
Y170079D03*
X1123031Y260630D03*
Y244882D03*
Y229134D03*
X1097441Y252756D03*
Y237008D03*
Y221260D03*
X1115157Y256693D03*
Y240945D03*
Y225197D03*
X1105315Y248819D03*
Y233071D03*
Y217323D03*
X1123031Y307874D03*
Y292126D03*
Y276378D03*
X1097441Y300000D03*
Y284252D03*
Y268504D03*
X1115157Y303937D03*
Y288189D03*
Y272441D03*
X1105315Y296063D03*
Y280315D03*
Y264567D03*
X1123031Y323622D03*
X1097441Y339371D03*
Y331496D03*
Y315748D03*
X1115157Y335434D03*
Y319685D03*
X1105315Y335434D03*
Y327559D03*
Y311811D03*
X1123031Y403543D03*
Y395669D03*
X1097441Y403543D03*
Y395669D03*
X1115157Y399606D03*
Y391732D03*
X1105315Y399606D03*
X1123031Y450787D03*
X1097441Y442913D03*
X1115157Y446850D03*
X1105315Y454724D03*
X1115157Y415354D03*
X1123031Y498031D03*
Y482283D03*
Y466535D03*
X1097441Y490157D03*
Y474409D03*
Y458661D03*
X1115157Y494094D03*
Y478346D03*
Y462598D03*
X1105315Y501968D03*
Y486220D03*
Y470472D03*
X1123031Y545275D03*
Y529527D03*
Y513779D03*
X1097441Y553149D03*
Y537401D03*
Y521653D03*
Y505905D03*
X1115157Y541338D03*
Y525590D03*
Y509842D03*
X1105315Y549212D03*
Y533464D03*
Y517716D03*
X1123031Y592519D03*
Y576771D03*
Y561023D03*
X1097441Y600393D03*
Y584645D03*
Y568897D03*
X1115157Y588582D03*
Y572834D03*
Y557086D03*
X1105315Y596456D03*
Y580708D03*
Y564960D03*
X1123031Y639763D03*
Y624015D03*
Y608267D03*
X1097441Y647637D03*
Y631889D03*
Y616141D03*
X1115157Y635826D03*
Y620078D03*
Y604330D03*
X1105315Y643700D03*
Y627952D03*
Y612204D03*
X1123031Y687007D03*
Y671259D03*
Y655511D03*
X1097441Y694881D03*
Y679133D03*
Y663385D03*
X1115157Y683070D03*
Y667322D03*
Y651574D03*
X1105315Y690944D03*
Y675196D03*
Y659448D03*
X1123031Y718504D03*
Y702755D03*
X1097441Y718504D03*
Y710629D03*
X1115157Y714567D03*
Y698818D03*
X1105315Y714567D03*
Y706692D03*
X1119419Y888607D03*
X1116419Y896107D03*
Y891107D03*
X1119419Y893607D03*
Y898607D03*
X1447834Y124507D03*
X1504527D03*
X1490354D03*
X1518701D03*
X1532874D03*
X1603425Y1105040D03*
Y1100040D03*
X1598425Y1102440D03*
Y1107440D03*
G54D16*
X64487Y201761D03*
X49937Y219661D03*
X54437D03*
X58937D03*
Y672417D03*
X54437D03*
X49937D03*
X64487Y654417D03*
X58175Y981325D03*
X58937Y1125173D03*
X54437D03*
X49937D03*
X64487Y1107173D03*
X53027Y1085073D03*
X119763Y550725D03*
Y546225D03*
Y555225D03*
X124263Y546225D03*
Y550725D03*
Y555225D03*
X188699Y200561D03*
X174149Y219661D03*
X178649D03*
X183149D03*
X185149Y617949D03*
X210000Y650000D03*
X182259Y672559D03*
X177759D03*
X173259D03*
X188399Y1102873D03*
X183149Y1125173D03*
X178649D03*
X174149D03*
X177105Y1094839D03*
X312912Y201661D03*
X298362Y219661D03*
X302862D03*
X307362D03*
Y672417D03*
X302862D03*
X298362D03*
X312912Y654417D03*
X307362Y1125173D03*
X302862D03*
X298362D03*
X313232Y1106499D03*
X301327Y1085173D03*
X437124Y201661D03*
X431574Y219661D03*
X427074D03*
X422574D03*
X437224Y654417D03*
X431574Y672417D03*
X427074D03*
X422574D03*
X456919Y1121725D03*
X447919D03*
X452419D03*
X441976Y1107576D03*
X446627Y1112973D03*
X504724Y1107073D03*
X546009Y187821D03*
X557057Y220152D03*
X553674Y220121D03*
X550219Y220111D03*
X555787Y672417D03*
X551287D03*
X546787D03*
Y1125173D03*
X551287D03*
X555787D03*
X549773Y1085173D03*
X561437Y197249D03*
Y654417D03*
X561337Y1107173D03*
X685250Y199493D03*
X674313Y220374D03*
X669813D03*
X682000Y628449D03*
X685550Y654417D03*
X679929Y673058D03*
X675429D03*
X670929D03*
X685250Y1102873D03*
X680000Y1125173D03*
X675500D03*
X671000D03*
X674700Y1098500D03*
X810301Y78654D03*
X805301D03*
X802801Y75654D03*
X807801D03*
X812801D03*
X809600Y1236300D03*
X804600D03*
X802100Y1233300D03*
X807100D03*
X812100D03*
X875132Y399200D03*
X878732D03*
Y395600D03*
X875132D03*
X878732Y392000D03*
X875132D03*
X880932Y406400D03*
Y402800D03*
X877332Y406400D03*
Y402800D03*
X880932Y410000D03*
X877332D03*
X876514Y1514948D03*
X942000Y1499500D03*
X950300D03*
X994305Y1566342D03*
Y1571942D03*
X1110447Y944217D03*
X1105447D03*
X1100447D03*
X1102947Y947217D03*
X1107947D03*
X1137446Y1024025D03*
Y1009852D03*
Y995679D03*
Y1038198D03*
Y1167343D03*
Y1224036D03*
Y1209863D03*
Y1195690D03*
Y1181516D03*
Y1266556D03*
Y1252383D03*
Y1238209D03*
Y1309076D03*
Y1323249D03*
Y1294902D03*
Y1280729D03*
Y1365769D03*
Y1351595D03*
Y1337422D03*
Y1394115D03*
Y1408288D03*
Y1379942D03*
X1158673Y1417067D03*
Y1407067D03*
Y1397067D03*
Y1387067D03*
Y1412067D03*
Y1402067D03*
Y1392067D03*
Y1382067D03*
X1330807Y181473D03*
X1311750Y187911D03*
X1326637Y226568D03*
X1316637D03*
X1321637D03*
X1326500Y627917D03*
X1311750Y640667D03*
X1318000Y680417D03*
X1323000D03*
X1328000D03*
X1326500Y1080673D03*
X1311750Y1093423D03*
X1328000Y1133173D03*
X1318000D03*
X1323000D03*
X1435963Y183833D03*
X1450713Y173049D03*
X1442213Y227661D03*
X1447213D03*
X1452213D03*
X1450713Y627817D03*
X1435963Y640667D03*
X1442213Y680417D03*
X1447213D03*
X1452213D03*
X1450713Y1080673D03*
X1442213Y1132173D03*
X1447213D03*
X1452213D03*
X1439750Y1096673D03*
X1560175Y187911D03*
X1566425Y227661D03*
X1571425D03*
X1555175Y642667D03*
X1566425Y677417D03*
X1571425D03*
X1556231Y1134920D03*
X1574925Y175061D03*
X1576425Y227661D03*
X1574925Y627817D03*
X1576425Y677417D03*
X1574925Y1080673D03*
X1684388Y187911D03*
X1699138Y175061D03*
X1690638Y227661D03*
X1695638D03*
X1700638D03*
X1684388Y638324D03*
X1699138Y627917D03*
X1699638Y675417D03*
X1689638D03*
X1694638D03*
X1697261Y1004347D03*
X1692761D03*
Y999847D03*
Y995347D03*
X1697261D03*
Y999847D03*
X1699138Y1080573D03*
X1700638Y1131673D03*
X1695638D03*
X1690638D03*
X1684388Y1091723D03*
X1808600Y187911D03*
Y640667D03*
X1774863Y1024725D03*
X1856219Y201661D03*
X1823350Y175161D03*
X1850669Y219661D03*
X1846169D03*
X1841669D03*
X1824850Y227661D03*
X1819850D03*
X1814850D03*
X1823350Y627917D03*
X1841669Y672417D03*
X1846169D03*
X1850669D03*
X1814850Y680417D03*
X1819850D03*
X1824850D03*
X1856219Y654417D03*
X1823350Y1080673D03*
X1858046Y1092779D03*
X1836953Y1103391D03*
X1850363Y1115037D03*
X1847506Y1118794D03*
X1851565Y1118784D03*
X1850280Y1111373D03*
X1816046Y1098532D03*
X1824850Y1133173D03*
X1814850D03*
X1819850D03*
X1896943Y894350D03*
G54D36*
X765124Y864089D03*
G54D24*
X133063Y1012725D03*
X199763Y600725D03*
X877265Y52540D03*
X881265D03*
X885265D03*
X873265D03*
X869265D03*
X869459Y56626D03*
Y61626D03*
X869044Y66985D03*
X873044D03*
X877139Y66926D03*
X885265Y60540D03*
Y56540D03*
X886073Y78824D03*
X885464Y83201D03*
X878549Y78905D03*
Y82905D03*
X869044Y70985D03*
X873044D03*
X882549Y76905D03*
Y80905D03*
X1169768Y730300D03*
Y723100D03*
Y726700D03*
G54D37*
X944882Y-63877D03*
G54D39*
X942126Y58465D03*
Y346457D03*
Y437598D03*
Y725590D03*
X1110236Y58465D03*
Y346457D03*
Y437598D03*
Y725590D03*
G54D31*
X496653Y80906D03*
X1465157D03*
G54D15*
X60540Y-85109D03*
X59536Y1573374D03*
X79000Y1301900D03*
X1826700Y77600D03*
X1865705Y1573374D03*
X1898432Y-93682D03*
X1908500Y1346800D03*
G54D13*
X15157Y474409D03*
X904921Y-25591D03*
X1894684Y474409D03*
G54D19*
X80019Y51968D03*
X127263Y20472D03*
X631200Y51968D03*
X678444Y20472D03*
X1250689Y51969D03*
X1297933Y20472D03*
X1801870Y51969D03*
X1849114Y20472D03*
G54D10*
X15157Y21653D03*
X904921Y564960D03*
X1894685Y21654D03*
G54D32*
X496653Y110552D03*
X1465157D03*
G54D25*
X173228Y1062992D03*
X421653Y1141732D03*
X670079Y1062992D03*
X1343701D03*
X1592126Y1141732D03*
X1840551Y1062992D03*
G54D33*
X503248Y829921D03*
X1673917D03*
G54D14*
X31496Y882677D03*
X168307Y646457D03*
X660236D03*
X718110Y820866D03*
X1366142Y646457D03*
X1462992Y866929D03*
X1602756Y646457D03*
X1903346Y803937D03*
G54D40*
X975787Y-25590D03*
G54D18*
X103642Y36220D03*
X654822D03*
X1274311D03*
X1825492D03*
G54D26*
X173228Y1114173D03*
X670079D03*
X1343700D03*
X1840551D03*
G54D41*
X975786Y564960D03*
G54D43*
X1104527Y1630792D03*
G54D17*
X53087Y179561D03*
Y632317D03*
X177399Y179661D03*
X301612D03*
Y632417D03*
X429224Y176300D03*
X425824Y632317D03*
X549937D03*
X677450Y185669D03*
X695413Y600755D03*
X699613D03*
X695413Y604955D03*
X691213Y613355D03*
X695413D03*
X699613D03*
X691213Y609155D03*
X695413D03*
X699613Y604955D03*
Y609155D03*
X703813Y592355D03*
Y596555D03*
Y600755D03*
Y613355D03*
Y609155D03*
Y604955D03*
X1039845Y1467746D03*
X1026345D03*
X1030845D03*
X1035345D03*
X1039845Y1463246D03*
X1026345D03*
X1030845D03*
X1035345D03*
X1005400Y1463157D03*
X1000900D03*
X996400D03*
X1009900D03*
X1005400Y1467657D03*
X1000900D03*
X996400D03*
X1009900D03*
X1035345Y1476746D03*
X1030845D03*
X1026345D03*
X1039845D03*
Y1472246D03*
X1026345D03*
X1030845D03*
X1035345D03*
X1005400Y1472157D03*
X1000900D03*
X996400D03*
X1009900D03*
Y1476657D03*
X1005400D03*
X1000900D03*
X996400D03*
X1023583Y1489593D03*
X995783D03*
X1014690Y1511178D03*
X1010190D03*
X1005690D03*
X1031790Y1511078D03*
X1027290D03*
X1019600Y1511100D03*
X1023583Y1501593D03*
Y1507593D03*
Y1495593D03*
X995783D03*
Y1501593D03*
Y1507593D03*
X1040583Y1517883D03*
X1031882Y1528985D03*
X1026459Y1528919D03*
X1014950D03*
X1020373Y1528985D03*
X1040583Y1523883D03*
X1062700Y1463100D03*
X1058200D03*
X1067200D03*
X1062700Y1467600D03*
X1058200D03*
X1067200D03*
X1053700Y1463100D03*
Y1467600D03*
X1062700Y1472100D03*
X1058200D03*
X1067200D03*
Y1476600D03*
X1058200D03*
X1062700D03*
X1053700Y1472100D03*
Y1476600D03*
X1078683Y1489593D03*
X1051383D03*
X1078683Y1495593D03*
Y1501593D03*
Y1507593D03*
Y1516593D03*
X1051383Y1495593D03*
Y1501593D03*
Y1507593D03*
X1078683Y1522593D03*
X1091089Y988592D03*
X1105262D03*
X1119435D03*
X1133609D03*
X1095026Y995678D03*
X1109199D03*
X1123372D03*
X1091089Y1002765D03*
X1105262D03*
X1119435D03*
X1133609D03*
X1095026Y1009852D03*
X1109199D03*
X1123372D03*
X1091089Y1016938D03*
X1105262D03*
X1119435D03*
X1133609D03*
X1095026Y1024025D03*
X1109199D03*
X1123372D03*
X1091089Y1031111D03*
X1105262D03*
X1119435D03*
X1133609D03*
X1095026Y1038198D03*
X1109199D03*
X1123372D03*
X1091089Y1160257D03*
Y1174430D03*
X1105262Y1160257D03*
Y1174430D03*
X1119435Y1160257D03*
Y1174430D03*
X1133609Y1160257D03*
Y1174430D03*
X1095026Y1167343D03*
X1109199D03*
X1123372D03*
X1091089Y1188603D03*
Y1202776D03*
Y1216949D03*
X1105262Y1188603D03*
Y1202776D03*
Y1216949D03*
X1119435Y1188603D03*
Y1202776D03*
Y1216949D03*
X1133609Y1188603D03*
Y1202776D03*
Y1216949D03*
X1095026Y1181516D03*
Y1195690D03*
Y1209863D03*
Y1224036D03*
X1109199Y1181516D03*
Y1195690D03*
Y1209863D03*
Y1224036D03*
X1123372Y1181516D03*
Y1195690D03*
Y1209863D03*
Y1224036D03*
X1091089Y1231123D03*
Y1245296D03*
Y1259469D03*
Y1273642D03*
X1105262Y1231123D03*
Y1245296D03*
Y1259469D03*
Y1273642D03*
X1119435Y1231123D03*
Y1245296D03*
Y1259469D03*
Y1273642D03*
X1133609Y1231123D03*
Y1245296D03*
Y1259469D03*
Y1273642D03*
X1095026Y1238209D03*
Y1252382D03*
Y1266556D03*
X1109199Y1238209D03*
Y1252382D03*
Y1266556D03*
X1123372Y1238209D03*
Y1252382D03*
Y1266556D03*
X1091089Y1287816D03*
Y1301989D03*
Y1316162D03*
X1105262Y1287816D03*
Y1301989D03*
Y1316162D03*
X1119435Y1287816D03*
Y1301989D03*
Y1316162D03*
X1133609Y1287816D03*
Y1301989D03*
Y1316162D03*
X1095026Y1280729D03*
Y1294902D03*
Y1309075D03*
Y1323249D03*
X1109199Y1280729D03*
Y1294902D03*
Y1309075D03*
Y1323249D03*
X1123372Y1280729D03*
Y1294902D03*
Y1309075D03*
Y1323249D03*
X1091089Y1330335D03*
Y1344508D03*
Y1358682D03*
Y1372855D03*
X1105262Y1330335D03*
Y1344508D03*
Y1358682D03*
Y1372855D03*
X1119435Y1330335D03*
Y1344508D03*
Y1358682D03*
Y1372855D03*
X1133609Y1330335D03*
Y1344508D03*
Y1358682D03*
Y1372855D03*
X1095026Y1337422D03*
Y1351595D03*
Y1365768D03*
X1109199Y1337422D03*
Y1351595D03*
Y1365768D03*
X1123372Y1337422D03*
Y1351595D03*
Y1365768D03*
X1091089Y1387028D03*
Y1401201D03*
X1105262Y1387028D03*
Y1401201D03*
X1119435Y1387028D03*
Y1401201D03*
X1133609Y1387028D03*
Y1401201D03*
X1095026Y1379942D03*
Y1394115D03*
Y1408288D03*
X1109199Y1379942D03*
Y1394115D03*
Y1408288D03*
X1123372Y1379942D03*
Y1394115D03*
Y1408288D03*
X1101457Y1601181D03*
X1119685D03*
X1108150D03*
X1126378D03*
X1378100Y530200D03*
Y534400D03*
X1365500Y538600D03*
X1369700D03*
X1365500Y534400D03*
X1369700D03*
X1373900D03*
X1365500Y530200D03*
X1369700D03*
X1373900D03*
X1386500Y534400D03*
Y530200D03*
X1382300D03*
Y534400D03*
X1850263Y964540D03*
X1850370Y960239D03*
X1845870D03*
X1845763Y964540D03*
Y956040D03*
X1850263D03*
G54D35*
X527179Y568731D03*
X602779Y552331D03*
X619560Y547201D03*
X623236Y562574D03*
X637592Y593186D03*
X641792D03*
Y597386D03*
X637592D03*
X633392Y593186D03*
Y597386D03*
X629192Y593186D03*
Y597386D03*
X641792Y605786D03*
Y601586D03*
X637592D03*
Y605786D03*
X633392D03*
Y601586D03*
X629192D03*
Y605786D03*
X809015Y661000D03*
X804015D03*
X808920Y652340D03*
Y656460D03*
X806515Y664000D03*
X922500Y1499700D03*
X988795Y1571058D03*
Y1576658D03*
X1036578Y1511210D03*
X1031799Y1534392D03*
X1026376Y1534326D03*
X1014867D03*
X1020290Y1534392D03*
X1040500Y1529290D03*
X1030709Y1619764D03*
X1014961D03*
X1002362D03*
Y1613858D03*
X1014961D03*
X1030709D03*
X1002362Y1642401D03*
X1014961D03*
X1030709D03*
X1002362Y1625669D03*
Y1636496D03*
Y1648307D03*
X1014961Y1625669D03*
Y1636496D03*
Y1648307D03*
X1030709Y1625669D03*
Y1636496D03*
Y1648307D03*
X1043307Y1619764D03*
Y1613858D03*
Y1642401D03*
Y1625669D03*
Y1636496D03*
Y1648307D03*
G54D29*
X436811Y67914D03*
X450984D03*
X429724Y92323D03*
Y106496D03*
Y78150D03*
X436811Y82087D03*
X450984D03*
X443898Y92323D03*
X458071D03*
X436811Y96260D03*
X450984D03*
X443898Y106496D03*
X458071D03*
X436811Y110433D03*
X450984D03*
X443898Y78150D03*
X458071D03*
X429724Y120670D03*
X443898D03*
X458071D03*
X465157Y67914D03*
X479331D03*
X465157Y82087D03*
Y96260D03*
Y110433D03*
X479331Y82087D03*
X472244Y92323D03*
X479331Y96260D03*
X472244Y106496D03*
X479331Y110433D03*
X472244Y78150D03*
Y120670D03*
X550197Y67914D03*
X536024D03*
X521850D03*
X514764Y116339D03*
Y110827D03*
Y102166D03*
Y96654D03*
Y78150D03*
X550197Y110433D03*
X536024D03*
X543110Y106496D03*
X528937D03*
X550197Y96260D03*
X536024D03*
X543110Y92323D03*
X528937D03*
X550197Y82087D03*
X536024D03*
X521850D03*
X543110Y78150D03*
X528937D03*
X557283Y106496D03*
Y92323D03*
Y78150D03*
X521850Y120276D03*
X543110Y120670D03*
X528937D03*
X557283D03*
X564370Y67914D03*
Y110433D03*
Y96260D03*
Y82087D03*
X1405315Y67914D03*
X1419488D03*
X1398228Y92323D03*
Y106496D03*
Y78150D03*
X1405315Y82087D03*
X1419488D03*
X1412402Y92323D03*
X1426575D03*
X1405315Y96260D03*
X1419488D03*
X1412402Y106496D03*
X1426575D03*
X1405315Y110433D03*
X1419488D03*
X1412402Y78150D03*
X1426575D03*
X1398228Y120670D03*
X1412402D03*
X1426575D03*
X1433661Y67914D03*
X1447835D03*
X1433661Y82087D03*
Y96260D03*
Y110433D03*
X1447835Y82087D03*
X1440748Y92323D03*
X1447835Y96260D03*
X1440748Y106496D03*
X1447835Y110433D03*
X1440748Y78150D03*
Y120670D03*
X1518701Y67914D03*
X1504528D03*
X1490354D03*
X1483268Y106496D03*
Y92323D03*
Y78150D03*
X1518701Y110433D03*
X1504528D03*
X1490354D03*
X1511614Y106496D03*
X1497441D03*
X1518701Y96260D03*
X1504528D03*
X1490354D03*
X1511614Y92323D03*
X1497441D03*
X1518701Y82087D03*
X1504528D03*
X1490354D03*
X1511614Y78150D03*
X1497441D03*
X1483268Y120670D03*
X1511614D03*
X1497441D03*
X1532874Y67914D03*
Y110433D03*
X1525787Y106496D03*
X1532874Y96260D03*
X1525787Y92323D03*
X1532874Y82087D03*
X1525787Y78150D03*
Y120670D03*
G36*
G01X149668Y380135D02*
G02X112735I-18466J-14781D01*
G03X119308Y392599I-29176J23351D01*
G02X143095I11894J-3623D01*
G03X149668Y380135I35749J10887D01*
G37*
G36*
G01X149667Y832891D02*
G02X112734I-18466J-14781D01*
G03X119307Y845355I-29176J23351D01*
G02X143094I11894J-3623D01*
G03X149667Y832891I35749J10887D01*
G37*
G36*
G01X149668Y1285647D02*
G02X112735I-18466J-14781D01*
G03X119308Y1298111I-29176J23351D01*
G02X143095I11894J-3623D01*
G03X149668Y1285647I35749J10887D01*
G37*
G36*
G01X397699Y380135D02*
G02X360766I-18467J-14781D01*
G03X367339Y392599I-29176J23351D01*
G02X391126I11894J-3623D01*
G03X397699Y380135I35749J10887D01*
G37*
G36*
G01Y832891D02*
G02X360766I-18467J-14781D01*
G03X367339Y845355I-29176J23351D01*
G02X391126I11894J-3623D01*
G03X397699Y832891I35749J10887D01*
G37*
G36*
G01Y1285647D02*
G02X360766I-18467J-14781D01*
G03X367339Y1298111I-29176J23351D01*
G02X391126I11894J-3623D01*
G03X397699Y1285647I35749J10887D01*
G37*
G36*
G01X645730Y380135D02*
G02X608797I-18466J-14781D01*
G03X615370Y392599I-29176J23351D01*
G02X639157I11893J-3623D01*
G03X645730Y380135I35749J10887D01*
G37*
G36*
G01Y832891D02*
G02X608797I-18466J-14781D01*
G03X615370Y845355I-29176J23351D01*
G02X639157I11893J-3623D01*
G03X645730Y832891I35749J10887D01*
G37*
G36*
G01Y1285647D02*
G02X608797I-18466J-14781D01*
G03X615370Y1298111I-29176J23351D01*
G02X639157I11893J-3623D01*
G03X645730Y1285647I35749J10887D01*
G37*
G36*
G01X814924Y265984D02*
G02X777991I-18467J-14781D01*
G03X784564Y278448I-29176J23351D01*
G02X808351I11893J-3623D01*
G03X814924Y265984I35749J10887D01*
G37*
G36*
G01Y738425D02*
G02X777991I-18467J-14781D01*
G03X784564Y750889I-29176J23351D01*
G02X808351I11893J-3623D01*
G03X814924Y738425I35749J10887D01*
G37*
G36*
G01X979885Y1090394D02*
G02X942952I-18467J-14781D01*
G03X949525Y1102858I-29176J23351D01*
G02X973312I11894J-3623D01*
G03X979885Y1090394I35749J10887D01*
G37*
G36*
G01Y1432913D02*
G02X942952I-18467J-14781D01*
G03X949525Y1445377I-29176J23351D01*
G02X973312I11894J-3623D01*
G03X979885Y1432913I35749J10887D01*
G37*
G36*
G01X1200357Y558898D02*
G02X1163424I-18467J-14781D01*
G03X1169997Y571362I-29176J23351D01*
G02X1193784I11894J-3623D01*
G03X1200357Y558898I35749J10887D01*
G37*
G36*
G01X1200337Y972261D02*
G02X1163404I-18467J-14781D01*
G03X1169977Y984725I-29176J23351D01*
G02X1193764I11894J-3623D01*
G03X1200337Y972261I35749J10887D01*
G37*
G36*
G01X1200357Y1562835D02*
G02X1163424I-18467J-14781D01*
G03X1169997Y1575299I-29176J23351D01*
G02X1193784I11894J-3623D01*
G03X1200357Y1562835I35749J10887D01*
G37*
G36*
G01X1320337Y380135D02*
G02X1283404I-18467J-14781D01*
G03X1289977Y392599I-29176J23351D01*
G02X1313764I11894J-3623D01*
G03X1320337Y380135I35749J10887D01*
G37*
G36*
G01Y832891D02*
G02X1283404I-18467J-14781D01*
G03X1289977Y845355I-29176J23351D01*
G02X1313764I11894J-3623D01*
G03X1320337Y832891I35749J10887D01*
G37*
G36*
G01Y1285647D02*
G02X1283404I-18467J-14781D01*
G03X1289977Y1298111I-29176J23351D01*
G02X1313764I11894J-3623D01*
G03X1320337Y1285647I35749J10887D01*
G37*
G36*
G01X1568368Y380135D02*
G02X1531435I-18467J-14781D01*
G03X1538008Y392599I-29176J23351D01*
G02X1561795I11894J-3623D01*
G03X1568368Y380135I35749J10887D01*
G37*
G36*
G01Y832891D02*
G02X1531435I-18467J-14781D01*
G03X1538008Y845355I-29176J23351D01*
G02X1561795I11894J-3623D01*
G03X1568368Y832891I35749J10887D01*
G37*
G36*
G01Y1285647D02*
G02X1531435I-18467J-14781D01*
G03X1538008Y1298111I-29176J23351D01*
G02X1561795I11894J-3623D01*
G03X1568368Y1285647I35749J10887D01*
G37*
G36*
G01X1816400Y380135D02*
G02X1779467I-18466J-14781D01*
G03X1786040Y392599I-29176J23351D01*
G02X1809827I11894J-3623D01*
G03X1816400Y380135I35749J10887D01*
G37*
G36*
G01Y832891D02*
G02X1779467I-18466J-14781D01*
G03X1786040Y845355I-29176J23351D01*
G02X1809827I11894J-3623D01*
G03X1816400Y832891I35749J10887D01*
G37*
G36*
G01Y1285647D02*
G02X1779467I-18466J-14781D01*
G03X1786040Y1298111I-29176J23351D01*
G02X1809827I11894J-3623D01*
G03X1816400Y1285647I35749J10887D01*
G37*
%LPC*%
G75*
G54D44*
G01X363248Y-425196D02*
Y-505196D01*
G01D02*
X1639148D01*
G01X359248Y-409196D02*
G02I-12000J0D01*
G01X354098D02*
G02I-6850J0D01*
G01X347248Y-425196D02*
Y-393196D01*
G01X363248Y-425196D02*
X1639148D01*
G01X363248Y-460696D02*
X1639148D01*
G01X363248Y-409196D02*
X331248D01*
G01X720748Y-425196D02*
Y-505196D01*
G01X858248Y-425196D02*
Y-505196D01*
G01X973248Y-425196D02*
Y-505196D01*
G01X1271648Y-425196D02*
Y-505196D01*
G01X1441648Y-425196D02*
Y-505196D01*
G01X1639148Y-425196D02*
Y-505196D01*
G01X1667148Y-409196D02*
G02I-12000J0D01*
G01X1661998D02*
G02I-6850J0D01*
G01X1655148Y-425196D02*
Y-393196D01*
G01X1671148Y-409196D02*
X1639148D01*
G54D45*
G01X394744Y-485863D02*
X395618Y-484988D01*
X396273Y-483530D01*
X396710Y-481487D01*
X396273Y-479738D01*
X395400Y-478571D01*
X393871Y-477696D01*
X387976D01*
Y-495196D01*
X395181D01*
X396710Y-494030D01*
X397583Y-492279D01*
X398020Y-490238D01*
X397583Y-488196D01*
X396273Y-486446D01*
X394744Y-485863D01*
X387976D01*
G01X407441Y-495196D02*
Y-483530D01*
G01Y-485863D02*
X408533Y-484696D01*
X409625Y-483821D01*
X411153Y-483530D01*
X412244Y-483821D01*
X413555Y-484696D01*
G01X423413Y-500446D02*
X424723Y-501029D01*
X426470Y-500446D01*
X427561Y-499280D01*
X428435Y-497821D01*
X429744Y-493155D01*
X432583Y-483530D01*
G01X425596D02*
X429744Y-493155D01*
G01X448991Y-484988D02*
X447463Y-483821D01*
X446153Y-483530D01*
X444406Y-484113D01*
X443096Y-485279D01*
X442223Y-487321D01*
X442004Y-489363D01*
X442223Y-491405D01*
X443096Y-493155D01*
X444406Y-494613D01*
X446153Y-495196D01*
X447681Y-494613D01*
X448991Y-493446D01*
G01X459723Y-487321D02*
X466710D01*
X466055Y-485279D01*
X464963Y-484113D01*
X463435Y-483530D01*
X461906Y-483821D01*
X460596Y-484696D01*
X459723Y-486738D01*
X459286Y-488488D01*
Y-490238D01*
X459723Y-491988D01*
X460815Y-493738D01*
X462125Y-494904D01*
X463653Y-495196D01*
X465181Y-494613D01*
X466710Y-492863D01*
G01X502801Y-479155D02*
X501491Y-478279D01*
X499963Y-477696D01*
X498216D01*
X496251Y-478571D01*
X494723Y-480029D01*
X493631Y-481780D01*
X492758Y-484696D01*
X492539Y-487321D01*
X492976Y-489946D01*
X493631Y-491696D01*
X494941Y-493446D01*
X496470Y-494613D01*
X497998Y-495196D01*
X499526D01*
X501055Y-494613D01*
X502365Y-493738D01*
X503457Y-492572D01*
G01X519428Y-495196D02*
Y-483530D01*
G01Y-485571D02*
X518555Y-484405D01*
X517244Y-483821D01*
X515716Y-483530D01*
X514188Y-484113D01*
X512878Y-485279D01*
X512004Y-487029D01*
X511568Y-489363D01*
X512004Y-491696D01*
X512878Y-493446D01*
X514188Y-494613D01*
X515716Y-495196D01*
X517244Y-494904D01*
X518555Y-494030D01*
X519428Y-492863D01*
G01X529286Y-495196D02*
Y-483530D01*
G01Y-486446D02*
X530160Y-484988D01*
X531470Y-483821D01*
X533216Y-483530D01*
X534744Y-483821D01*
X536055Y-484988D01*
X536710Y-487029D01*
Y-495196D01*
G01X545913Y-500446D02*
X547223Y-501029D01*
X548970Y-500446D01*
X550061Y-499280D01*
X550935Y-497821D01*
X552244Y-493155D01*
X555083Y-483530D01*
G01X548096D02*
X552244Y-493155D01*
G01X567998Y-495196D02*
X566688Y-494904D01*
X565378Y-493738D01*
X564504Y-491696D01*
X564068Y-489363D01*
X564504Y-487029D01*
X565378Y-484988D01*
X566688Y-483821D01*
X567998Y-483530D01*
X569308Y-483821D01*
X570618Y-484988D01*
X571491Y-487029D01*
X571710Y-489363D01*
X571491Y-491696D01*
X570618Y-493738D01*
X569308Y-494904D01*
X567998Y-495196D01*
G01X581786D02*
Y-483530D01*
G01Y-486446D02*
X582660Y-484988D01*
X583970Y-483821D01*
X585716Y-483530D01*
X587244Y-483821D01*
X588555Y-484988D01*
X589210Y-487029D01*
Y-495196D01*
G01X616350D02*
Y-477696D01*
X624646D01*
G01X621590Y-486154D02*
X616350D01*
G01X637998Y-495779D02*
X637561Y-495488D01*
Y-494904D01*
X637998Y-494613D01*
X638435Y-494904D01*
Y-495488D01*
X637998Y-495779D01*
G01X650695Y-495196D02*
Y-477696D01*
X655061D01*
X656808Y-478571D01*
X658118Y-479738D01*
X659210Y-481487D01*
X660083Y-483530D01*
X660301Y-486446D01*
X660083Y-489363D01*
X659210Y-491405D01*
X658118Y-493155D01*
X656808Y-494321D01*
X655061Y-495196D01*
X650695D01*
G01X668631D02*
Y-477696D01*
X673871D01*
X675618Y-478571D01*
X676928Y-480613D01*
X677365Y-482946D01*
X676928Y-485279D01*
X675836Y-487029D01*
X673871Y-487905D01*
X668631D01*
G01X692244Y-485863D02*
X693118Y-484988D01*
X693773Y-483530D01*
X694210Y-481487D01*
X693773Y-479738D01*
X692900Y-478571D01*
X691371Y-477696D01*
X685476D01*
Y-495196D01*
X692681D01*
X694210Y-494030D01*
X695083Y-492279D01*
X695520Y-490238D01*
X695083Y-488196D01*
X693773Y-486446D01*
X692244Y-485863D01*
X685476D01*
G01X501071Y-450196D02*
Y-432696D01*
X506748Y-447279D01*
X512425Y-432696D01*
Y-450196D01*
G01X524248D02*
X522938Y-449904D01*
X521628Y-448738D01*
X520754Y-446696D01*
X520318Y-444363D01*
X520754Y-442029D01*
X521628Y-439988D01*
X522938Y-438821D01*
X524248Y-438530D01*
X525558Y-438821D01*
X526868Y-439988D01*
X527741Y-442029D01*
X527960Y-444363D01*
X527741Y-446696D01*
X526868Y-448738D01*
X525558Y-449904D01*
X524248Y-450196D01*
G01X545678Y-432696D02*
Y-450196D01*
G01Y-447572D02*
X544805Y-449030D01*
X543494Y-449904D01*
X541966Y-450196D01*
X540220Y-449613D01*
X538910Y-448155D01*
X538036Y-446405D01*
X537818Y-444363D01*
X538036Y-442321D01*
X538910Y-440571D01*
X540220Y-439113D01*
X541966Y-438530D01*
X543494Y-438821D01*
X544586Y-439405D01*
X545678Y-440571D01*
G01X555973Y-442321D02*
X562960D01*
X562305Y-440279D01*
X561213Y-439113D01*
X559685Y-438530D01*
X558156Y-438821D01*
X556846Y-439696D01*
X555973Y-441738D01*
X555536Y-443488D01*
Y-445238D01*
X555973Y-446988D01*
X557065Y-448738D01*
X558375Y-449904D01*
X559903Y-450196D01*
X561431Y-449613D01*
X562960Y-447863D01*
G01X576748Y-450196D02*
Y-432696D01*
G01X754448Y-495196D02*
Y-477696D01*
X751828Y-481196D01*
G01Y-495196D02*
X757068D01*
G01X767800Y-487905D02*
X769328Y-485863D01*
X770638Y-484696D01*
X772385Y-484113D01*
X773913Y-484696D01*
X775005Y-485863D01*
X775878Y-487613D01*
X776096Y-489654D01*
X775878Y-491405D01*
X775005Y-493155D01*
X773694Y-494613D01*
X772166Y-495196D01*
X770420Y-494613D01*
X768891Y-492863D01*
X768018Y-490238D01*
X767800Y-487321D01*
X768236Y-483530D01*
X768891Y-481487D01*
X769983Y-479446D01*
X771511Y-477988D01*
X773040Y-477696D01*
X774568Y-478279D01*
X775660Y-479738D01*
G01X784645Y-491696D02*
X785954Y-493738D01*
X787701Y-494904D01*
X789666Y-495196D01*
X791413Y-494904D01*
X793160Y-493446D01*
X794251Y-491696D01*
X794470Y-489946D01*
X794033Y-487905D01*
X792505Y-486446D01*
X790976Y-485863D01*
X789011D01*
G01X790976D02*
X792286Y-484988D01*
X793378Y-483530D01*
X793815Y-481780D01*
X793378Y-480029D01*
X792286Y-478571D01*
X790321Y-477696D01*
X788356Y-477988D01*
X786391Y-479155D01*
G01X806948Y-495196D02*
Y-477696D01*
X804328Y-481196D01*
G01Y-495196D02*
X809568D01*
G01X819645Y-492572D02*
X820954Y-494030D01*
X822483Y-494904D01*
X824448Y-495196D01*
X826413Y-494613D01*
X827941Y-493446D01*
X829033Y-491405D01*
X829251Y-489071D01*
X828815Y-486738D01*
X827723Y-485279D01*
X826194Y-484113D01*
X824666Y-483821D01*
X823138Y-484113D01*
X821173Y-485279D01*
X821828Y-477696D01*
X827723D01*
G01X741331Y-450196D02*
Y-432696D01*
X746571D01*
X748318Y-433571D01*
X749628Y-435613D01*
X750065Y-437946D01*
X749628Y-440279D01*
X748536Y-442029D01*
X746571Y-442905D01*
X741331D01*
G01X768001Y-434155D02*
X766691Y-433279D01*
X765163Y-432696D01*
X763416D01*
X761451Y-433571D01*
X759923Y-435029D01*
X758831Y-436780D01*
X757958Y-439696D01*
X757739Y-442321D01*
X758176Y-444946D01*
X758831Y-446696D01*
X760141Y-448446D01*
X761670Y-449613D01*
X763198Y-450196D01*
X764726D01*
X766255Y-449613D01*
X767565Y-448738D01*
X768657Y-447572D01*
G01X782444Y-440863D02*
X783318Y-439988D01*
X783973Y-438530D01*
X784410Y-436487D01*
X783973Y-434738D01*
X783100Y-433571D01*
X781571Y-432696D01*
X775676D01*
Y-450196D01*
X782881D01*
X784410Y-449030D01*
X785283Y-447279D01*
X785720Y-445238D01*
X785283Y-443196D01*
X783973Y-441446D01*
X782444Y-440863D01*
X775676D01*
G01X791648Y-456029D02*
X804748D01*
G01X810676Y-450196D02*
Y-432696D01*
X820720Y-450196D01*
Y-432696D01*
G01X833198Y-450196D02*
X831451Y-449904D01*
X829923Y-448738D01*
X828613Y-446988D01*
X827739Y-444946D01*
X827303Y-442613D01*
Y-440279D01*
X827739Y-437946D01*
X828613Y-435904D01*
X829923Y-434155D01*
X831451Y-432988D01*
X833198Y-432696D01*
X834944Y-432988D01*
X836473Y-434155D01*
X837783Y-435904D01*
X838657Y-437946D01*
X839093Y-440279D01*
Y-442613D01*
X838657Y-444946D01*
X837783Y-446988D01*
X836473Y-448738D01*
X834944Y-449904D01*
X833198Y-450196D01*
G01X884039Y-432696D02*
X889498Y-450196D01*
X894957Y-432696D01*
G01X911365Y-450196D02*
X902631D01*
Y-432696D01*
X911365D01*
G01X907871Y-441154D02*
X902631D01*
G01X920131Y-450196D02*
Y-432696D01*
X925590D01*
X927336Y-433571D01*
X928428Y-434738D01*
X928865Y-437071D01*
X928428Y-439405D01*
X927118Y-440863D01*
X925590Y-441738D01*
X920131D01*
G01X925590D02*
X928865Y-450196D01*
G01X941998Y-450779D02*
X941561Y-450488D01*
Y-449904D01*
X941998Y-449613D01*
X942435Y-449904D01*
Y-450488D01*
X941998Y-450779D01*
G01X915748Y-495196D02*
Y-477696D01*
X913128Y-481196D01*
G01Y-495196D02*
X918368D01*
G01X1082981Y-477696D02*
Y-495196D01*
X1091715D01*
G01X1100700Y-487905D02*
X1102228Y-485863D01*
X1103538Y-484696D01*
X1105285Y-484113D01*
X1106813Y-484696D01*
X1107905Y-485863D01*
X1108778Y-487613D01*
X1108996Y-489654D01*
X1108778Y-491405D01*
X1107905Y-493155D01*
X1106594Y-494613D01*
X1105066Y-495196D01*
X1103320Y-494613D01*
X1101791Y-492863D01*
X1100918Y-490238D01*
X1100700Y-487321D01*
X1101136Y-483530D01*
X1101791Y-481487D01*
X1102883Y-479446D01*
X1104411Y-477988D01*
X1105940Y-477696D01*
X1107468Y-478279D01*
X1108560Y-479738D01*
G01X1116889Y-477696D02*
X1122348Y-495196D01*
X1127807Y-477696D01*
G01X1144651Y-479155D02*
X1143341Y-478279D01*
X1141813Y-477696D01*
X1140066D01*
X1138101Y-478571D01*
X1136573Y-480029D01*
X1135481Y-481780D01*
X1134608Y-484696D01*
X1134389Y-487321D01*
X1134826Y-489946D01*
X1135481Y-491696D01*
X1136791Y-493446D01*
X1138320Y-494613D01*
X1139848Y-495196D01*
X1141376D01*
X1142905Y-494613D01*
X1144215Y-493738D01*
X1145307Y-492572D01*
G01X1162151Y-479155D02*
X1160841Y-478279D01*
X1159313Y-477696D01*
X1157566D01*
X1155601Y-478571D01*
X1154073Y-480029D01*
X1152981Y-481780D01*
X1152108Y-484696D01*
X1151889Y-487321D01*
X1152326Y-489946D01*
X1152981Y-491696D01*
X1154291Y-493446D01*
X1155820Y-494613D01*
X1157348Y-495196D01*
X1158876D01*
X1160405Y-494613D01*
X1161715Y-493738D01*
X1162807Y-492572D01*
G01X1082981Y-432696D02*
Y-450196D01*
X1091715D01*
G01X1108778D02*
Y-438530D01*
G01Y-440571D02*
X1107905Y-439405D01*
X1106594Y-438821D01*
X1105066Y-438530D01*
X1103538Y-439113D01*
X1102228Y-440279D01*
X1101354Y-442029D01*
X1100918Y-444363D01*
X1101354Y-446696D01*
X1102228Y-448446D01*
X1103538Y-449613D01*
X1105066Y-450196D01*
X1106594Y-449904D01*
X1107905Y-449030D01*
X1108778Y-447863D01*
G01X1117763Y-455446D02*
X1119073Y-456029D01*
X1120820Y-455446D01*
X1121911Y-454280D01*
X1122785Y-452821D01*
X1124094Y-448155D01*
X1126933Y-438530D01*
G01X1119946D02*
X1124094Y-448155D01*
G01X1136573Y-442321D02*
X1143560D01*
X1142905Y-440279D01*
X1141813Y-439113D01*
X1140285Y-438530D01*
X1138756Y-438821D01*
X1137446Y-439696D01*
X1136573Y-441738D01*
X1136136Y-443488D01*
Y-445238D01*
X1136573Y-446988D01*
X1137665Y-448738D01*
X1138975Y-449904D01*
X1140503Y-450196D01*
X1142031Y-449613D01*
X1143560Y-447863D01*
G01X1154291Y-450196D02*
Y-438530D01*
G01Y-440863D02*
X1155383Y-439696D01*
X1156475Y-438821D01*
X1158003Y-438530D01*
X1159094Y-438821D01*
X1160405Y-439696D01*
G01X1312898Y-495196D02*
X1311151Y-494904D01*
X1309623Y-493738D01*
X1308313Y-491988D01*
X1307439Y-489946D01*
X1307003Y-487613D01*
Y-485279D01*
X1307439Y-482946D01*
X1308313Y-480904D01*
X1309623Y-479155D01*
X1311151Y-477988D01*
X1312898Y-477696D01*
X1314644Y-477988D01*
X1316173Y-479155D01*
X1317483Y-480904D01*
X1318357Y-482946D01*
X1318793Y-485279D01*
Y-487613D01*
X1318357Y-489946D01*
X1317483Y-491988D01*
X1316173Y-493738D01*
X1314644Y-494904D01*
X1312898Y-495196D01*
G01X1314644Y-490529D02*
X1317265Y-495196D01*
G01X1325595Y-477696D02*
Y-490238D01*
X1326468Y-492863D01*
X1328215Y-494613D01*
X1330398Y-495196D01*
X1332581Y-494613D01*
X1334328Y-492863D01*
X1335201Y-490238D01*
Y-477696D01*
G01X1345278D02*
X1350518D01*
G01X1347898D02*
Y-495196D01*
G01X1345278D02*
X1350518D01*
G01X1360376D02*
Y-477696D01*
X1370420Y-495196D01*
Y-477696D01*
G01X1387701Y-479155D02*
X1386391Y-478279D01*
X1384863Y-477696D01*
X1383116D01*
X1381151Y-478571D01*
X1379623Y-480029D01*
X1378531Y-481780D01*
X1377658Y-484696D01*
X1377439Y-487321D01*
X1377876Y-489946D01*
X1378531Y-491696D01*
X1379841Y-493446D01*
X1381370Y-494613D01*
X1382898Y-495196D01*
X1384426D01*
X1385955Y-494613D01*
X1387265Y-493738D01*
X1388357Y-492572D01*
G01X1400398Y-495196D02*
Y-487321D01*
X1396031Y-477696D01*
G01X1404765D02*
X1400398Y-487321D01*
G01X1290595Y-450196D02*
Y-432696D01*
X1294961D01*
X1296708Y-433571D01*
X1298018Y-434738D01*
X1299110Y-436487D01*
X1299983Y-438530D01*
X1300201Y-441446D01*
X1299983Y-444363D01*
X1299110Y-446405D01*
X1298018Y-448155D01*
X1296708Y-449321D01*
X1294961Y-450196D01*
X1290595D01*
G01X1309623Y-442321D02*
X1316610D01*
X1315955Y-440279D01*
X1314863Y-439113D01*
X1313335Y-438530D01*
X1311806Y-438821D01*
X1310496Y-439696D01*
X1309623Y-441738D01*
X1309186Y-443488D01*
Y-445238D01*
X1309623Y-446988D01*
X1310715Y-448738D01*
X1312025Y-449904D01*
X1313553Y-450196D01*
X1315081Y-449613D01*
X1316610Y-447863D01*
G01X1327123Y-448155D02*
X1328215Y-449321D01*
X1329743Y-450196D01*
X1331053D01*
X1332363Y-449613D01*
X1333236Y-448738D01*
X1333673Y-447572D01*
X1333455Y-445821D01*
X1332581Y-444946D01*
X1328651Y-443196D01*
X1327778Y-441154D01*
X1328215Y-439696D01*
X1329088Y-438821D01*
X1330398Y-438530D01*
X1331708Y-438821D01*
X1333018Y-439696D01*
G01X1347898Y-438530D02*
Y-450196D01*
G01Y-433863D02*
X1347461Y-433571D01*
Y-432988D01*
X1347898Y-432696D01*
X1348335Y-432988D01*
Y-433571D01*
X1347898Y-433863D01*
G01X1362341Y-454571D02*
X1363870Y-455738D01*
X1365616Y-456029D01*
X1367144Y-455738D01*
X1368455Y-454280D01*
X1369328Y-452238D01*
Y-438530D01*
G01Y-440863D02*
X1368455Y-439696D01*
X1367144Y-438821D01*
X1365616Y-438530D01*
X1363870Y-439113D01*
X1362778Y-440279D01*
X1361904Y-442321D01*
X1361468Y-444363D01*
X1361686Y-446113D01*
X1362560Y-448155D01*
X1363870Y-449613D01*
X1365616Y-450196D01*
X1366926Y-449904D01*
X1368455Y-448738D01*
X1369328Y-447572D01*
G01X1379186Y-450196D02*
Y-438530D01*
G01Y-441446D02*
X1380060Y-439988D01*
X1381370Y-438821D01*
X1383116Y-438530D01*
X1384644Y-438821D01*
X1385955Y-439988D01*
X1386610Y-442029D01*
Y-450196D01*
G01X1397123Y-442321D02*
X1404110D01*
X1403455Y-440279D01*
X1402363Y-439113D01*
X1400835Y-438530D01*
X1399306Y-438821D01*
X1397996Y-439696D01*
X1397123Y-441738D01*
X1396686Y-443488D01*
Y-445238D01*
X1397123Y-446988D01*
X1398215Y-448738D01*
X1399525Y-449904D01*
X1401053Y-450196D01*
X1402581Y-449613D01*
X1404110Y-447863D01*
G01X1414841Y-450196D02*
Y-438530D01*
G01Y-440863D02*
X1415933Y-439696D01*
X1417025Y-438821D01*
X1418553Y-438530D01*
X1419644Y-438821D01*
X1420955Y-439696D01*
G01X1461598Y-477696D02*
X1459851Y-478279D01*
X1458541Y-479738D01*
X1457668Y-481487D01*
X1457013Y-483821D01*
X1456795Y-486446D01*
X1457013Y-489071D01*
X1457668Y-491405D01*
X1458541Y-493155D01*
X1459851Y-494613D01*
X1461598Y-495196D01*
X1463344Y-494613D01*
X1464655Y-493155D01*
X1465528Y-491405D01*
X1466183Y-489071D01*
X1466401Y-486446D01*
X1466183Y-483821D01*
X1465528Y-481487D01*
X1464655Y-479738D01*
X1463344Y-478279D01*
X1461598Y-477696D01*
G01X1474950Y-487905D02*
X1476478Y-485863D01*
X1477788Y-484696D01*
X1479535Y-484113D01*
X1481063Y-484696D01*
X1482155Y-485863D01*
X1483028Y-487613D01*
X1483246Y-489654D01*
X1483028Y-491405D01*
X1482155Y-493155D01*
X1480844Y-494613D01*
X1479316Y-495196D01*
X1477570Y-494613D01*
X1476041Y-492863D01*
X1475168Y-490238D01*
X1474950Y-487321D01*
X1475386Y-483530D01*
X1476041Y-481487D01*
X1477133Y-479446D01*
X1478661Y-477988D01*
X1480190Y-477696D01*
X1481718Y-478279D01*
X1482810Y-479738D01*
G01X1492668Y-495779D02*
X1500528Y-477696D01*
G01X1514098D02*
X1512351Y-478279D01*
X1511041Y-479738D01*
X1510168Y-481487D01*
X1509513Y-483821D01*
X1509295Y-486446D01*
X1509513Y-489071D01*
X1510168Y-491405D01*
X1511041Y-493155D01*
X1512351Y-494613D01*
X1514098Y-495196D01*
X1515844Y-494613D01*
X1517155Y-493155D01*
X1518028Y-491405D01*
X1518683Y-489071D01*
X1518901Y-486446D01*
X1518683Y-483821D01*
X1518028Y-481487D01*
X1517155Y-479738D01*
X1515844Y-478279D01*
X1514098Y-477696D01*
G01X1527886Y-493155D02*
X1529415Y-494613D01*
X1531161Y-495196D01*
X1532908Y-494613D01*
X1534436Y-492863D01*
X1535528Y-490238D01*
X1535965Y-487613D01*
Y-484405D01*
X1535528Y-481780D01*
X1534436Y-479446D01*
X1533126Y-478279D01*
X1531598Y-477696D01*
X1529851Y-478279D01*
X1528541Y-479446D01*
X1527668Y-481196D01*
X1527231Y-483530D01*
X1527668Y-485571D01*
X1528760Y-487613D01*
X1530070Y-488780D01*
X1531598Y-489071D01*
X1533344Y-488488D01*
X1534655Y-487029D01*
X1535965Y-484405D01*
G01X1545168Y-495779D02*
X1553028Y-477696D01*
G01X1562450Y-480613D02*
X1563760Y-478863D01*
X1565288Y-477988D01*
X1567035Y-477696D01*
X1569218Y-478279D01*
X1570746Y-479738D01*
X1571183Y-481487D01*
X1570965Y-483238D01*
X1570091Y-484696D01*
X1565725Y-487613D01*
X1563760Y-489654D01*
X1562450Y-492572D01*
X1562013Y-495196D01*
X1571183D01*
G01X1584098Y-477696D02*
X1582351Y-478279D01*
X1581041Y-479738D01*
X1580168Y-481487D01*
X1579513Y-483821D01*
X1579295Y-486446D01*
X1579513Y-489071D01*
X1580168Y-491405D01*
X1581041Y-493155D01*
X1582351Y-494613D01*
X1584098Y-495196D01*
X1585844Y-494613D01*
X1587155Y-493155D01*
X1588028Y-491405D01*
X1588683Y-489071D01*
X1588901Y-486446D01*
X1588683Y-483821D01*
X1588028Y-481487D01*
X1587155Y-479738D01*
X1585844Y-478279D01*
X1584098Y-477696D01*
G01X1601598Y-495196D02*
Y-477696D01*
X1598978Y-481196D01*
G01Y-495196D02*
X1604218D01*
G01X1618661D02*
X1619098Y-491405D01*
X1619753Y-488196D01*
X1620626Y-485279D01*
X1621718Y-482071D01*
X1623465Y-477696D01*
X1614731D01*
G01X1509295Y-450196D02*
Y-432696D01*
X1513661D01*
X1515408Y-433571D01*
X1516718Y-434738D01*
X1517810Y-436487D01*
X1518683Y-438530D01*
X1518901Y-441446D01*
X1518683Y-444363D01*
X1517810Y-446405D01*
X1516718Y-448155D01*
X1515408Y-449321D01*
X1513661Y-450196D01*
X1509295D01*
G01X1535528D02*
Y-438530D01*
G01Y-440571D02*
X1534655Y-439405D01*
X1533344Y-438821D01*
X1531816Y-438530D01*
X1530288Y-439113D01*
X1528978Y-440279D01*
X1528104Y-442029D01*
X1527668Y-444363D01*
X1528104Y-446696D01*
X1528978Y-448446D01*
X1530288Y-449613D01*
X1531816Y-450196D01*
X1533344Y-449904D01*
X1534655Y-449030D01*
X1535528Y-447863D01*
G01X1549098Y-432696D02*
Y-450196D01*
G01X1546041Y-438530D02*
X1552155D01*
G01X1563323Y-442321D02*
X1570310D01*
X1569655Y-440279D01*
X1568563Y-439113D01*
X1567035Y-438530D01*
X1565506Y-438821D01*
X1564196Y-439696D01*
X1563323Y-441738D01*
X1562886Y-443488D01*
Y-445238D01*
X1563323Y-446988D01*
X1564415Y-448738D01*
X1565725Y-449904D01*
X1567253Y-450196D01*
X1568781Y-449613D01*
X1570310Y-447863D01*
M02*
